G04 ================== begin FILE IDENTIFICATION RECORD ==================*
G04 Layout Name:  F:/<user>/2022/FB/R4006-TIMING/brd/gerber-3/R4006-B0001-02_R01.brd*
G04 Film Name:    R4006-B0001-02_R01_L09*
G04 File Format:  Gerber RS274X*
G04 File Origin:  Cadence Allegro 17.2-S079*
G04 Origin Date:  Fri Feb 25 18:14:43 2022*
G04 *
G04 Layer:  ETCH/L09_GND4*
G04 Layer:  PIN/L09_GND4*
G04 Layer:  VIA CLASS/L09_GND4*
G04 Layer:  MANUFACTURING/L09_GND4*
G04 Layer:  MANUFACTURING/CELESTICA_LEGEND*
G04 *
G04 Offset:    (0.00 0.00)*
G04 Mirror:    No*
G04 Mode:      Negative*
G04 Rotation:  0*
G04 FullContactRelief:  No*
G04 UndefLineWidth:     6.00*
G04 ================== end FILE IDENTIFICATION RECORD ====================*
%FSLAX55Y55*MOIN*%
%IR0*IPPOS*OFA0.00000B0.00000*MIA0B0*SFA1.00000B1.00000*%
%AMMACRO17*
4,1,20,-.005,-.04399,
-.009177,-.042751,
-.013075,-.040805,
-.016576,-.038212,
-.019573,-.03505,
-.021977,-.031416,
-.023712,-.02742,
-.024727,-.023183,
-.025,-.0195,
-.025,-.006,
-.02,-.006,
-.02,-.0195,
-.019696,-.022972,
-.018794,-.026338,
-.017321,-.029497,
-.015322,-.032352,
-.012858,-.034816,
-.010003,-.036815,
-.006845,-.038288,
-.005,-.03886,
-.005,-.04399,
270.*
4,1,20,.005,-.04399,
.005,-.03886,
.008286,-.037699,
.01132,-.035985,
.014011,-.033769,
.016276,-.031121,
.018047,-.028119,
.019269,-.024855,
.019907,-.021429,
.02,-.0195,
.02,-.006,
.025,-.006,
.025,-.0195,
.02462,-.02384,
.023493,-.028048,
.021651,-.031997,
.019153,-.035566,
.016072,-.038647,
.012503,-.041145,
.008554,-.042987,
.005,-.04399,
270.*
4,1,20,-.025,.006,
-.025,.0195,
-.02462,.02384,
-.023493,.028048,
-.021651,.031997,
-.019153,.035566,
-.016072,.038647,
-.012503,.041145,
-.008554,.042987,
-.005,.04399,
-.005,.03886,
-.008286,.037699,
-.01132,.035985,
-.014011,.033769,
-.016276,.031121,
-.018047,.028119,
-.019269,.024855,
-.019907,.021429,
-.02,.0195,
-.02,.006,
-.025,.006,
270.*
4,1,20,.02,.006,
.02,.0195,
.019696,.022972,
.018794,.026338,
.017321,.029497,
.015322,.032352,
.012858,.034816,
.010003,.036815,
.006845,.038288,
.005,.03886,
.005,.04399,
.009177,.042751,
.013075,.040805,
.016576,.038212,
.019573,.03505,
.021977,.031416,
.023712,.02742,
.024727,.023183,
.025,.0195,
.025,.006,
.02,.006,
270.*
%
%ADD17MACRO17*%
%ADD22C,.03*%
%ADD16C,.02*%
%ADD12C,.032*%
%ADD14C,.024*%
%ADD20C,.026*%
%ADD21C,.028*%
%ADD15C,.082*%
%ADD10C,.018*%
%ADD19C,.039*%
%ADD28C,.099*%
%AMMACRO24*
4,1,18,.03817,.02827,
.042499,.021212,
.045537,.01351,
.047191,.005398,
.047412,-.002879,
.046191,-.011068,
.043568,-.018921,
.03962,-.026199,
.03817,-.02827,
.04174,-.03184,
.046635,-.024108,
.050113,-.015644,
.052068,-.006704,
.052441,.002439,
.051221,.011508,
.048444,.020228,
.044196,.028333,
.04174,.03184,
.03817,.02827,
0.0*
4,1,18,.02827,-.03817,
.021212,-.042499,
.01351,-.045537,
.005398,-.047191,
-.002879,-.047412,
-.011068,-.046191,
-.018921,-.043568,
-.026199,-.03962,
-.02827,-.03817,
-.03184,-.04174,
-.024108,-.046635,
-.015644,-.050113,
-.006704,-.052068,
.002439,-.052441,
.011508,-.051221,
.020228,-.048444,
.028333,-.044196,
.03184,-.04174,
.02827,-.03817,
0.0*
4,1,18,-.03817,-.02827,
-.042499,-.021212,
-.045537,-.01351,
-.047191,-.005398,
-.047412,.002879,
-.046191,.011068,
-.043568,.018921,
-.03962,.026199,
-.03817,.02827,
-.04174,.03184,
-.046635,.024108,
-.050113,.015644,
-.052068,.006704,
-.052441,-.002439,
-.051221,-.011508,
-.048444,-.020228,
-.044196,-.028333,
-.04174,-.03184,
-.03817,-.02827,
0.0*
4,1,18,-.02827,.03817,
-.021212,.042499,
-.01351,.045537,
-.005398,.047191,
.002879,.047412,
.011068,.046191,
.018921,.043568,
.026199,.03962,
.02827,.03817,
.03184,.04174,
.024108,.046635,
.015644,.050113,
.006704,.052068,
-.002439,.052441,
-.011508,.051221,
-.020228,.048444,
-.028333,.044196,
-.03184,.04174,
-.02827,.03817,
0.0*
%
%ADD24MACRO24*%
%AMMACRO31*
4,1,17,.0205,.01342,
.022519,.009656,
.023854,.005599,
.024464,.001372,
.02433,-.002897,
.023457,-.007078,
.021872,-.011044,
.0205,-.01342,
.02409,-.01702,
.02668,-.012578,
.028458,-.007754,
.029373,-.002695,
.029394,.002447,
.028523,.007514,
.026785,.012353,
.024233,.016816,
.02409,.01702,
.0205,.01342,
90.*
4,1,17,.01342,-.0205,
.009656,-.022519,
.005599,-.023854,
.001372,-.024464,
-.002897,-.02433,
-.007078,-.023457,
-.011044,-.021872,
-.01342,-.0205,
-.01702,-.02409,
-.012578,-.02668,
-.007754,-.028458,
-.002695,-.029373,
.002447,-.029394,
.007514,-.028523,
.012353,-.026785,
.016816,-.024233,
.01702,-.02409,
.01342,-.0205,
90.*
4,1,17,-.0205,-.01342,
-.022519,-.009656,
-.023854,-.005599,
-.024464,-.001372,
-.02433,.002897,
-.023457,.007078,
-.021872,.011044,
-.0205,.01342,
-.02409,.01702,
-.02668,.012578,
-.028458,.007754,
-.029373,.002695,
-.029394,-.002447,
-.028523,-.007514,
-.026785,-.012353,
-.024233,-.016816,
-.02409,-.01702,
-.0205,-.01342,
90.*
4,1,17,-.01342,.0205,
-.009656,.022519,
-.005599,.023854,
-.001372,.024464,
.002897,.02433,
.007078,.023457,
.011044,.021872,
.01342,.0205,
.01702,.02409,
.012578,.02668,
.007754,.028458,
.002695,.029373,
-.002447,.029394,
-.007514,.028523,
-.012353,.026785,
-.016816,.024233,
-.01702,.02409,
-.01342,.0205,
90.*
%
%ADD31MACRO31*%
%AMMACRO26*
4,1,18,.07318,.05409,
.081461,.040561,
.087267,.025799,
.090421,.010253,
.090828,-.005604,
.088475,-.021291,
.083433,-.036331,
.075857,-.050267,
.07318,-.05409,
.07675,-.05766,
.085597,-.043457,
.091842,-.027933,
.095297,-.01156,
.095857,.005164,
.093504,.021731,
.08831,.037637,
.080433,.052401,
.07675,.05766,
.07318,.05409,
0.0*
4,1,18,.05409,-.07318,
.040561,-.081461,
.025799,-.087267,
.010253,-.090421,
-.005604,-.090828,
-.021291,-.088475,
-.036331,-.083433,
-.050267,-.075857,
-.05409,-.07318,
-.05766,-.07675,
-.043457,-.085597,
-.027933,-.091842,
-.01156,-.095297,
.005164,-.095857,
.021731,-.093504,
.037637,-.08831,
.052401,-.080433,
.05766,-.07675,
.05409,-.07318,
0.0*
4,1,18,-.07318,-.05409,
-.081461,-.040561,
-.087267,-.025799,
-.090421,-.010253,
-.090828,.005604,
-.088475,.021291,
-.083433,.036331,
-.075857,.050267,
-.07318,.05409,
-.07675,.05766,
-.085597,.043457,
-.091842,.027933,
-.095297,.01156,
-.095857,-.005164,
-.093504,-.021731,
-.08831,-.037637,
-.080433,-.052401,
-.07675,-.05766,
-.07318,-.05409,
0.0*
4,1,18,-.05409,.07318,
-.040561,.081461,
-.025799,.087267,
-.010253,.090421,
.005604,.090828,
.021291,.088475,
.036331,.083433,
.050267,.075857,
.05409,.07318,
.05766,.07675,
.043457,.085597,
.027933,.091842,
.01156,.095297,
-.005164,.095857,
-.021731,.093504,
-.037637,.08831,
-.052401,.080433,
-.05766,.07675,
-.05409,.07318,
0.0*
%
%ADD26MACRO26*%
%AMMACRO11*
4,1,18,.03185,.02336,
.035423,.017474,
.037919,.011058,
.039263,.004305,
.039414,-.002578,
.038368,-.009383,
.036155,-.015903,
.032845,-.02194,
.03185,-.02336,
.03542,-.02694,
.03956,-.02038,
.042498,-.013201,
.044145,-.005621,
.04445,.00213,
.043405,.009817,
.041041,.017205,
.03743,.02407,
.03542,.02694,
.03185,.02336,
0.0*
4,1,18,.02336,-.03185,
.017474,-.035423,
.011058,-.037919,
.004305,-.039263,
-.002578,-.039414,
-.009383,-.038368,
-.015903,-.036155,
-.02194,-.032845,
-.02336,-.03185,
-.02694,-.03542,
-.02038,-.03956,
-.013201,-.042498,
-.005621,-.044145,
.00213,-.04445,
.009817,-.043405,
.017205,-.041041,
.02407,-.03743,
.02694,-.03542,
.02336,-.03185,
0.0*
4,1,18,-.03185,-.02336,
-.035423,-.017474,
-.037919,-.011058,
-.039263,-.004305,
-.039414,.002578,
-.038368,.009383,
-.036155,.015903,
-.032845,.02194,
-.03185,.02336,
-.03542,.02694,
-.03956,.02038,
-.042498,.013201,
-.044145,.005621,
-.04445,-.00213,
-.043405,-.009817,
-.041041,-.017205,
-.03743,-.02407,
-.03542,-.02694,
-.03185,-.02336,
0.0*
4,1,18,-.02336,.03185,
-.017474,.035423,
-.011058,.037919,
-.004305,.039263,
.002578,.039414,
.009383,.038368,
.015903,.036155,
.02194,.032845,
.02336,.03185,
.02694,.03542,
.02038,.03956,
.013201,.042498,
.005621,.044145,
-.00213,.04445,
-.009817,.043405,
-.017205,.041041,
-.02407,.03743,
-.02694,.03542,
-.02336,.03185,
0.0*
%
%ADD11MACRO11*%
%AMMACRO30*
4,1,20,-.005,-.03799,
-.009177,-.036751,
-.013075,-.034805,
-.016576,-.032212,
-.019573,-.02905,
-.021977,-.025416,
-.023712,-.02142,
-.024727,-.017183,
-.025,-.0135,
-.025,-.005,
-.02,-.005,
-.02,-.0135,
-.019696,-.016972,
-.018794,-.020338,
-.017321,-.023497,
-.015322,-.026352,
-.012858,-.028816,
-.010003,-.030815,
-.006845,-.032288,
-.005,-.03286,
-.005,-.03799,
90.*
4,1,20,.005,-.03799,
.005,-.03286,
.008286,-.031699,
.01132,-.029985,
.014011,-.027769,
.016276,-.025121,
.018047,-.022119,
.019269,-.018855,
.019907,-.015429,
.02,-.0135,
.02,-.005,
.025,-.005,
.025,-.0135,
.02462,-.01784,
.023493,-.022048,
.021651,-.025997,
.019153,-.029566,
.016072,-.032647,
.012503,-.035145,
.008554,-.036987,
.005,-.03799,
90.*
4,1,20,-.025,.005,
-.025,.0135,
-.02462,.01784,
-.023493,.022048,
-.021651,.025997,
-.019153,.029566,
-.016072,.032647,
-.012503,.035145,
-.008554,.036987,
-.005,.03799,
-.005,.03286,
-.008286,.031699,
-.01132,.029985,
-.014011,.027769,
-.016276,.025121,
-.018047,.022119,
-.019269,.018855,
-.019907,.015429,
-.02,.0135,
-.02,.005,
-.025,.005,
90.*
4,1,20,.02,.005,
.02,.0135,
.019696,.016972,
.018794,.020338,
.017321,.023497,
.015322,.026352,
.012858,.028816,
.010003,.030815,
.006845,.032288,
.005,.03286,
.005,.03799,
.009177,.036751,
.013075,.034805,
.016576,.032212,
.019573,.02905,
.021977,.025416,
.023712,.02142,
.024727,.017183,
.025,.0135,
.025,.005,
.02,.005,
90.*
%
%ADD30MACRO30*%
%ADD23C,.102*%
%ADD13C,.15*%
%ADD29C,.143*%
%ADD25C,.125*%
%AMMACRO18*
4,1,15,.01428,.00721,
.015315,.004621,
.015885,.001891,
.015972,-.000896,
.015574,-.003656,
.014702,-.006305,
.01428,-.00721,
.01796,-.01089,
.019578,-.007606,
.020601,-.004091,
.020999,-.000451,
.020758,.003202,
.019887,.006758,
.018411,.010109,
.01796,.01089,
.01428,.00721,
270.*
4,1,15,.00721,-.01428,
.004621,-.015315,
.001891,-.015885,
-.000896,-.015972,
-.003656,-.015574,
-.006305,-.014702,
-.00721,-.01428,
-.01089,-.01796,
-.007606,-.019578,
-.004091,-.020601,
-.000451,-.020999,
.003202,-.020758,
.006758,-.019887,
.010109,-.018411,
.01089,-.01796,
.00721,-.01428,
270.*
4,1,15,-.01428,-.00721,
-.015315,-.004621,
-.015885,-.001891,
-.015972,.000896,
-.015574,.003656,
-.014702,.006305,
-.01428,.00721,
-.01796,.01089,
-.019578,.007606,
-.020601,.004091,
-.020999,.000451,
-.020758,-.003202,
-.019887,-.006758,
-.018411,-.010109,
-.01796,-.01089,
-.01428,-.00721,
270.*
4,1,15,-.00721,.01428,
-.004621,.015315,
-.001891,.015885,
.000896,.015972,
.003656,.015574,
.006305,.014702,
.00721,.01428,
.01089,.01796,
.007606,.019578,
.004091,.020601,
.000451,.020999,
-.003202,.020758,
-.006758,.019887,
-.010109,.018411,
-.01089,.01796,
-.00721,.01428,
270.*
%
%ADD18MACRO18*%
%AMMACRO27*
4,1,18,.0371,.0272,
.04126,.020344,
.044166,.012871,
.04573,.005006,
.045904,-.003011,
.044684,-.010936,
.042106,-.01853,
.038249,-.02556,
.0371,-.0272,
.04067,-.03077,
.045395,-.02324,
.048741,-.015004,
.050606,-.006313,
.050934,.002571,
.049713,.011376,
.046983,.019836,
.042824,.027693,
.04067,.03077,
.0371,.0272,
270.*
4,1,18,.0272,-.0371,
.020344,-.04126,
.012871,-.044166,
.005006,-.04573,
-.003011,-.045904,
-.010936,-.044684,
-.01853,-.042106,
-.02556,-.038249,
-.0272,-.0371,
-.03077,-.04067,
-.02324,-.045395,
-.015004,-.048741,
-.006313,-.050606,
.002571,-.050934,
.011376,-.049713,
.019836,-.046983,
.027693,-.042824,
.03077,-.04067,
.0272,-.0371,
270.*
4,1,18,-.0371,-.0272,
-.04126,-.020344,
-.044166,-.012871,
-.04573,-.005006,
-.045904,.003011,
-.044684,.010936,
-.042106,.01853,
-.038249,.02556,
-.0371,.0272,
-.04067,.03077,
-.045395,.02324,
-.048741,.015004,
-.050606,.006313,
-.050934,-.002571,
-.049713,-.011376,
-.046983,-.019836,
-.042824,-.027693,
-.04067,-.03077,
-.0371,-.0272,
270.*
4,1,18,-.0272,.0371,
-.020344,.04126,
-.012871,.044166,
-.005006,.04573,
.003011,.045904,
.010936,.044684,
.01853,.042106,
.02556,.038249,
.0272,.0371,
.03077,.04067,
.02324,.045395,
.015004,.048741,
.006313,.050606,
-.002571,.050934,
-.011376,.049713,
-.019836,.046983,
-.027693,.042824,
-.03077,.04067,
-.0272,.0371,
270.*
%
%ADD27MACRO27*%
%ADD32C,.01*%
%ADD33C,.005*%
%ADD34C,.006*%
%ADD38R,.07002X.03002*%
%ADD41R,.07004X.03002*%
%ADD36R,.07002X.03004*%
%ADD53C,.40006*%
%ADD52R,.07004X.03004*%
%ADD43R,.03004X.07004*%
%ADD39R,.02802X.06002*%
%ADD47C,.12406*%
%ADD51R,.06002X.02804*%
%ADD45R,.02802X.06004*%
%ADD42R,.06004X.02802*%
%ADD40R,.02804X.02402*%
%ADD35R,.02402X.02804*%
%ADD50R,.06004X.02804*%
%ADD44R,.02404X.02804*%
%ADD37R,.02804X.02404*%
%ADD46C,.14906*%
%ADD49O,.02606X.06543*%
%ADD48C,.16806*%
G75*
%LPD*%
G75*
G36*
G01X-10000Y-10000D02*
X670039D01*
Y447598D01*
X-10000D01*
Y-10000D01*
G37*
%LPC*%
G75*
G36*
G01X309201Y26200D02*
X231744D01*
Y29331D01*
G03X218256I-6744J0D01*
G01Y26200D01*
X180169D01*
Y43012D01*
G03X159791I-10189J0D01*
G01Y21654D01*
G02X158858Y20721I-933J0D01*
G01X135236D01*
G02X134303Y21654I0J933D01*
G01Y46260D01*
G03X127362Y53201I-6941J0D01*
G01X62992D01*
G03X56051Y46260I0J-6941D01*
G01Y21654D01*
G02X55118Y20721I-933J0D01*
G01X3937D01*
G02X3004Y21654I0J933D01*
G01Y433661D01*
G02X3937Y434594I933J0D01*
G01X656102D01*
G02X657035Y433661I0J-933D01*
G01Y287647D01*
G03X652239Y282678I177J-4969D01*
G01Y241437D01*
G03X657035Y236468I4972J0D01*
G01Y54134D01*
G02X656102Y53201I-933J0D01*
G01X316142D01*
G03X309201Y46260I0J-6941D01*
G01Y26200D01*
G37*
%LPD*%
G75*
G36*
G01X600696Y115350D02*
G02X617500Y124503I16804J-10849D01*
G02X637503Y104500I0J-20003D01*
G02X636283Y97621I-20004J0D01*
G02X636500Y96501I-2783J-1120D01*
G01Y96500D01*
G02X634273Y93601I-3000J0D01*
G02X617500Y84497I-16773J10899D01*
G02X597497Y104500I0J20003D01*
G02X598437Y110560I20003J0D01*
G02X597846Y112349I2413J1789D01*
G01Y112350D01*
G02X600696Y115350I3004J0D01*
G37*
G36*
G01X395067Y171866D02*
X399004D01*
G02Y169262I0J-1302D01*
G01X395067D01*
G02Y171866I0J1302D01*
G37*
G36*
G01X402942Y167930D02*
X406879D01*
G02Y165324I0J-1303D01*
G01X402942D01*
G02Y167930I0J1303D01*
G37*
G36*
G01X387193D02*
X391130D01*
G02Y165324I0J-1303D01*
G01X387193D01*
G02Y167930I0J1303D01*
G37*
G36*
G01X395067Y163992D02*
X399004D01*
G02Y161388I0J-1302D01*
G01X395067D01*
G02Y163992I0J1302D01*
G37*
G36*
G01X446248Y185008D02*
X442311D01*
G02Y187614I0J1303D01*
G01X446248D01*
G02Y185008I0J-1303D01*
G37*
G36*
G01X461996Y132496D02*
X465933D01*
G02Y129890I0J-1303D01*
G01X461996D01*
G02Y132496I0J1303D01*
G37*
G36*
G01X446248Y141702D02*
G02Y144308I0J1303D01*
G01X450185D01*
G02Y141702I0J-1303D01*
G01X446248D01*
G37*
G36*
G01X387193Y157450D02*
G02Y160056I0J1303D01*
G01X391130D01*
G02Y157450I0J-1303D01*
G01X387193D01*
G37*
G36*
G01X402942Y149576D02*
G02Y152182I0J1303D01*
G01X406879D01*
G02Y149576I0J-1303D01*
G01X402942D01*
G37*
G36*
G01X310516Y87500D02*
X312500Y89484D01*
X316747Y85237D01*
X314763Y83253D01*
X310516Y87500D01*
G37*
G36*
G01X395067Y153514D02*
G02Y156118I0J1302D01*
G01X399004D01*
G02Y153514I0J-1302D01*
G01X395067D01*
G37*
G36*
G01X387193Y149576D02*
G02Y152182I0J1303D01*
G01X391130D01*
G02Y149576I0J-1303D01*
G01X387193D01*
G37*
G36*
G01X395067Y145640D02*
G02Y148244I0J1302D01*
G01X399004D01*
G02Y145640I0J-1302D01*
G01X395067D01*
G37*
G36*
G01X387193Y141702D02*
G02Y144308I0J1303D01*
G01X391130D01*
G02Y141702I0J-1303D01*
G01X387193D01*
G37*
G36*
G01X469870Y145640D02*
G02Y148244I0J1302D01*
G01X473807D01*
G02Y145640I0J-1302D01*
G01X469870D01*
G37*
G54D38*
X455731Y122167D03*
X439251Y116599D03*
X353065Y104707D03*
G54D41*
X403250Y116099D03*
G54D36*
X281801Y198700D03*
G54D53*
X599000Y209400D03*
G54D52*
X343400Y108500D03*
G54D43*
X284500Y185900D03*
X240508Y71500D03*
X337500Y117800D03*
G54D39*
X345301Y191499D03*
X365101Y189959D03*
G54D47*
X268567Y255943D03*
X146067Y268043D03*
X143567Y106043D03*
X268567Y112143D03*
G54D51*
X268307Y76300D03*
X283455D03*
G54D45*
X264339Y36900D03*
X295835D03*
X280087D03*
X295835Y46500D03*
X619961Y226074D03*
G54D42*
X324310Y190299D03*
G54D40*
X353300Y193149D03*
X357500D03*
Y188649D03*
X353300D03*
G54D35*
X280055Y62600D03*
X297303Y58400D03*
X302303Y62600D03*
X297303D03*
X302303Y58400D03*
X239311Y62600D03*
X234311D03*
Y58400D03*
X239311D03*
X270807D03*
X265807D03*
X270807Y62600D03*
X265807D03*
X285055Y58400D03*
X280055D03*
X285055Y62600D03*
G54D50*
X71900Y357500D03*
X108900Y382500D03*
X248622Y76300D03*
X364100Y92000D03*
G54D44*
X279500Y188000D03*
Y183800D03*
X251122Y58400D03*
X246122D03*
X251122Y62600D03*
X246122D03*
G54D37*
X283850Y194500D03*
X279650D03*
G54D46*
X640039Y65354D03*
X29528Y373031D03*
Y36811D03*
X640039Y417835D03*
G54D49*
X473807Y137098D03*
G54D48*
X634055Y334449D03*
Y367519D03*
G54D17*
X24807Y335985D03*
Y347245D03*
X43705Y331655D03*
Y351576D03*
G54D22*
X76100Y154400D03*
X75950Y164200D03*
X73600Y252500D03*
X68600Y274000D03*
X75500Y282500D03*
X63800Y274000D03*
X70500Y419000D03*
X75580Y419004D03*
X88300Y163900D03*
X98000Y420000D03*
X90000Y420500D03*
X85500D03*
X112880Y73020D03*
X126000Y67000D03*
Y62000D03*
X131500Y290500D03*
X148500Y62500D03*
X139500D03*
X145900Y75200D03*
X142070Y77900D03*
X142000Y69535D03*
X136000Y290500D03*
X138250Y372250D03*
X148500Y376000D03*
X138500Y387500D03*
X153500Y390500D03*
X163300Y382900D03*
X151100Y386300D03*
X152100Y399300D03*
X151530Y406300D03*
X153150Y394590D03*
X160600Y417400D03*
X152200Y416300D03*
X183170Y56390D03*
X180620Y77890D03*
X180390Y70720D03*
X180910Y63390D03*
X187598Y36900D03*
X189500Y33000D03*
X186000D03*
X187598Y28900D03*
X191535Y41200D03*
X198135Y36500D03*
X195000Y54550D03*
X203000Y75000D03*
X196497Y76502D03*
X210500Y30500D03*
X207880Y78740D03*
X214810Y78810D03*
X212800Y289500D03*
X218500Y301700D03*
X213500D03*
X208500D03*
X224500Y302000D03*
X222000Y330000D03*
X254527Y33900D03*
X240508Y69900D03*
Y73100D03*
X263300Y52200D03*
X284500Y184300D03*
Y187500D03*
X283400Y198700D03*
X280200D03*
X289600Y330100D03*
X307300Y61300D03*
X298700Y327000D03*
Y323500D03*
X293200Y329500D03*
X322200Y320500D03*
X310600Y335000D03*
X322200Y338500D03*
X341799Y108500D03*
X337500Y116200D03*
Y119400D03*
X349000Y82500D03*
X344999Y108500D03*
X351464Y104707D03*
X354664D03*
X352300Y175000D03*
X358400Y182700D03*
X345930Y217000D03*
X354800Y285600D03*
X355000Y328000D03*
X375500Y350500D03*
X380400Y81600D03*
X381700Y92400D03*
X383128Y178372D03*
X383000Y346600D03*
X388500Y391000D03*
X393500D03*
X388500Y400000D03*
X393500D03*
X393000Y418500D03*
X401650Y116099D03*
X404850D03*
X405463Y383000D03*
X410463D03*
X398500Y391000D03*
Y400000D03*
X403000Y418500D03*
X398000D03*
X415463Y383000D03*
X414000Y419000D03*
X422337Y424000D03*
X416800D03*
X437650Y116599D03*
X440850D03*
X442500Y336089D03*
X439500Y341500D03*
X443000Y386500D03*
X432000Y396500D03*
X457330Y122167D03*
X454130D03*
X490970Y133500D03*
Y138500D03*
X488500Y359000D03*
X500500Y271100D03*
X500000Y278799D03*
X533000Y95000D03*
Y99500D03*
X522400Y270700D03*
X522600Y276200D03*
X528500Y299000D03*
X532300Y425700D03*
X549500Y69400D03*
X548158Y228033D03*
X545250Y256300D03*
X539977Y275124D03*
X540318Y270436D03*
X537500Y296607D03*
X568600Y76000D03*
X553122Y227979D03*
X559500Y228000D03*
X566700Y227500D03*
X552000Y367597D03*
Y371141D03*
X555200Y367597D03*
Y371141D03*
X552000Y374684D03*
Y378227D03*
X555200D03*
Y374684D03*
X572500Y60301D03*
X572870Y67570D03*
X577100Y227900D03*
X581400Y262100D03*
Y272100D03*
Y282100D03*
X581500Y302100D03*
X576200Y342500D03*
X597000Y199900D03*
X591902Y200300D03*
X601902Y200100D03*
X594153Y220500D03*
X589953Y236600D03*
X591000Y261500D03*
X590500Y301500D03*
X606902Y200400D03*
X633500Y205906D03*
X625800Y215874D03*
X633000Y267000D03*
G54D12*
X11264Y152264D03*
X9000Y279000D03*
Y286000D03*
X12500Y91000D03*
Y96000D03*
Y101000D03*
Y106000D03*
X19100Y148798D03*
X23600D03*
X28100D03*
X13620Y148720D03*
X13000Y157000D03*
X12500Y162000D03*
Y209500D03*
Y204500D03*
Y214500D03*
Y219500D03*
X11963Y266437D03*
X19000Y262500D03*
X24200Y262508D03*
X28700D03*
X12500Y261500D03*
X15000Y279000D03*
X28700Y274300D03*
X13000Y273327D03*
X28500Y302000D03*
X28000Y296500D03*
X16000Y297500D03*
X24100Y310900D03*
X18000Y314500D03*
X13000Y318700D03*
X11976Y323524D03*
X28000Y327000D03*
X44500Y73500D03*
X45500Y104390D03*
X41500Y127500D03*
X41409Y132591D03*
X41600Y148798D03*
X32600Y148700D03*
X37100Y148798D03*
X45500Y182500D03*
X45000Y213000D03*
X46000Y219500D03*
X40500Y262000D03*
X33200Y262508D03*
X43000Y255500D03*
X37400Y282900D03*
X29000Y291500D03*
X43000Y314500D03*
X33000D03*
X44500Y309000D03*
X39500D03*
X34500D03*
X35500Y327000D03*
X59600Y60200D03*
X55500Y59000D03*
X50500Y60228D03*
X60100Y73000D03*
X57000Y83500D03*
X51500D03*
X50500Y104800D03*
X59000Y96500D03*
X62500Y100500D03*
X57500Y101500D03*
X62500Y117000D03*
X48390Y128312D03*
X53740Y126000D03*
X55922Y140543D03*
X46500Y133000D03*
X47500Y140500D03*
X60500Y152000D03*
X51400Y161600D03*
X54130Y152500D03*
X60600Y157000D03*
X48957Y153619D03*
X53500Y183500D03*
X58000Y213500D03*
X54000D03*
X48000Y200500D03*
X53000D03*
X63000Y206000D03*
Y210500D03*
Y215000D03*
X49600Y213455D03*
X51452Y219900D03*
X53200Y240187D03*
X54590Y266870D03*
X48232Y264530D03*
X48500Y252500D03*
X55200Y253500D03*
X52500Y278000D03*
X52800Y272000D03*
X62000Y307000D03*
Y323500D03*
X55000Y336000D03*
Y355400D03*
X62500Y365000D03*
Y369000D03*
Y373000D03*
Y378000D03*
Y382000D03*
X60300Y407100D03*
Y401100D03*
Y395100D03*
Y413100D03*
X71500Y77000D03*
X76400Y87200D03*
X76321Y78300D03*
X78500Y82250D03*
X73500Y112500D03*
X67000Y109000D03*
X79000Y100500D03*
X74000D03*
X67500Y114500D03*
X68000Y119000D03*
X73500D03*
X69500Y130000D03*
X74000D03*
X75000Y141700D03*
X64445Y168945D03*
X69000Y187500D03*
Y193000D03*
X69023Y198524D03*
X67400Y227100D03*
X71400Y232900D03*
X68000Y235500D03*
X67700Y240200D03*
X72400Y264600D03*
X69500Y257800D03*
X64248Y258000D03*
X64500Y296750D03*
X78000Y291500D03*
X66000Y318500D03*
X79000Y315500D03*
X66000Y323500D03*
X78635Y324492D03*
X79500Y341790D03*
Y348500D03*
X72000Y346300D03*
X73000Y365000D03*
X69500D03*
X66000D03*
X66500Y382000D03*
X70500D03*
X80700Y399200D03*
Y404200D03*
X71300D03*
Y399200D03*
X76000D03*
Y404200D03*
X71300Y394200D03*
X76000D03*
X80700D03*
X64300Y407600D03*
Y401600D03*
Y395600D03*
X80500Y420500D03*
X80700Y409200D03*
X76000D03*
X71300D03*
X64300Y413600D03*
X86000Y63100D03*
X84200Y75000D03*
X82100Y79300D03*
X96500Y98000D03*
X92250Y97750D03*
X89000Y110500D03*
X93500D03*
X90500Y105000D03*
X84000Y100500D03*
X87000Y130000D03*
Y120000D03*
X93500Y125000D03*
X87000Y125500D03*
X93500Y130000D03*
X90500Y144500D03*
X95500Y145500D03*
X96500Y140000D03*
X91500D03*
X88400Y154900D03*
X93900Y155200D03*
X95200Y151000D03*
X88500Y149000D03*
X94500Y163000D03*
X98500Y159000D03*
X91000Y181500D03*
X88250Y177250D03*
X83500Y178000D03*
X97500Y172000D03*
X98500Y165500D03*
X92000Y173000D03*
X83500D03*
X95500Y192000D03*
X83500Y193000D03*
Y188500D03*
X90500D03*
X94500Y197000D03*
X90500Y193500D03*
X97500Y214000D03*
X84500Y218000D03*
X95700Y227500D03*
X98500Y218500D03*
X96000Y241000D03*
X85700Y236500D03*
X96500Y235500D03*
X98500Y256661D03*
X83200Y260300D03*
X86900Y267200D03*
X95900Y278900D03*
X94500Y312500D03*
X95000Y321500D03*
X82500Y339000D03*
X82951Y327940D03*
X97500Y341000D03*
X95100Y351900D03*
X83000Y352500D03*
Y344500D03*
X95000D03*
X82800Y364600D03*
X94500Y373000D03*
Y369000D03*
Y364500D03*
X90500D03*
X86500D03*
X91500Y359500D03*
X83500Y360000D03*
X82800Y384600D03*
X94500Y380500D03*
X94000Y384500D03*
X90500D03*
X86500D03*
X94500Y376500D03*
X85400Y404200D03*
Y399200D03*
Y394200D03*
X96800Y408100D03*
X92800D03*
Y402100D03*
X96800D03*
Y396100D03*
X92800D03*
X85400Y409200D03*
X96800Y414100D03*
X92800D03*
X111330Y59810D03*
X99000Y175500D03*
Y188500D03*
Y197500D03*
Y206500D03*
Y201500D03*
Y260025D03*
X112500Y302000D03*
X107500D03*
X112500Y290000D03*
X102500D03*
Y302000D03*
X105410Y318500D03*
X115253Y306247D03*
X101500Y341000D03*
X104019Y347425D03*
X103000Y351500D03*
X113000Y344500D03*
X114000Y352000D03*
X104500Y377000D03*
X125000Y76500D03*
X126000Y72000D03*
X117500Y290000D03*
X129000Y321500D03*
X126000Y318000D03*
X129500Y328000D03*
X130000Y349664D03*
X119000Y352000D03*
X124500D03*
X140100Y306900D03*
X135000Y312000D03*
X149500Y311034D03*
X140700Y320000D03*
X146000Y334000D03*
X141916Y333916D03*
X137000Y364000D03*
X145000Y359000D03*
X141000Y379500D03*
X148500Y380000D03*
X145000Y378000D03*
X135200Y408400D03*
X140000Y401000D03*
X135100Y412600D03*
X143500Y418000D03*
X153270Y58400D03*
X151200Y75191D03*
X160500Y75500D03*
Y71500D03*
X156800Y301100D03*
X156600Y295000D03*
X156000Y320500D03*
Y316500D03*
Y325000D03*
Y329000D03*
X159100Y354600D03*
X166700Y343800D03*
X151500Y358000D03*
X159100Y382600D03*
X163600Y378600D03*
X157900Y387400D03*
X158500Y405200D03*
X160582Y410000D03*
X160550Y413400D03*
X151700Y411300D03*
X173170Y70840D03*
X182600Y289500D03*
X179500Y294600D03*
X176500Y290000D03*
X178000Y309500D03*
X173800Y324100D03*
X175000Y394500D03*
X177000Y398000D03*
X188900Y54960D03*
X195900Y332500D03*
X213500Y54000D03*
X208160Y73990D03*
X204770Y67780D03*
X207800Y83010D03*
X219200Y338800D03*
X205000Y348800D03*
Y353800D03*
X215000Y343800D03*
X219000Y348800D03*
Y392500D03*
X215500D03*
X216500Y396000D03*
X220000D03*
X223500Y58250D03*
X231000Y68000D03*
Y71500D03*
X228500Y75500D03*
Y79000D03*
X226500Y334000D03*
X222500Y324500D03*
X238000Y345000D03*
X225500Y347500D03*
X230000D03*
X249000Y290300D03*
X255400Y290100D03*
X247000Y344500D03*
X251000D03*
X255000D03*
X259500Y54700D03*
X259000Y344500D03*
X296400Y70200D03*
X307500Y160500D03*
X303500Y164000D03*
X298284Y175184D03*
X300995Y187611D03*
X297772Y188694D03*
X297000Y310500D03*
X301000Y317000D03*
X293700Y317300D03*
X309000Y164500D03*
X312500Y160500D03*
X320500Y170000D03*
X324000Y227500D03*
Y220750D03*
X312500Y225400D03*
X311900Y229900D03*
Y243400D03*
X312000Y269000D03*
Y256500D03*
Y264500D03*
X317500Y295500D03*
X321000D03*
X324500D03*
X310500Y321000D03*
X312500Y307500D03*
X310600Y326000D03*
X325000Y363000D03*
X320000Y398500D03*
X323000Y401500D03*
X336000Y61060D03*
X340500Y63500D03*
Y87000D03*
X338000Y102500D03*
X332550Y213550D03*
X327923Y221577D03*
X335153Y217875D03*
X333500Y258900D03*
X338500Y259000D03*
X339500Y282000D03*
X341000Y304000D03*
X332500Y306500D03*
X328000D03*
X341400Y323500D03*
X340500Y361300D03*
X332500D03*
X336500D03*
X339200Y380300D03*
X339300Y384000D03*
Y387700D03*
X340500Y391600D03*
X336300Y423200D03*
Y415200D03*
Y419200D03*
X340800Y415200D03*
X349500Y61000D03*
X354500Y60920D03*
X345500Y87000D03*
X354000Y82500D03*
X344000Y103000D03*
X347500Y141500D03*
X350000D03*
X352500D03*
X355000D03*
X357000Y154200D03*
X353482Y154157D03*
X350085Y154300D03*
X346500Y174000D03*
X344500Y181500D03*
X349128Y186628D03*
X344000Y212000D03*
X355500Y218000D03*
Y220500D03*
Y225500D03*
Y223000D03*
X351000Y233243D03*
Y237000D03*
X352500Y260000D03*
X348500D03*
X357680Y271780D03*
X357000Y295500D03*
X356000Y302300D03*
X349000Y295500D03*
X346000Y306500D03*
X351000Y308000D03*
X355000Y337000D03*
X348418Y361300D03*
X344500D03*
X347700Y381600D03*
X347000Y391200D03*
X359800Y397700D03*
X347600Y398800D03*
X348279Y405678D03*
X353000Y416500D03*
X350000Y419500D03*
X349500Y415000D03*
X346000Y416000D03*
X343700Y409900D03*
X348863Y410500D03*
X369310Y109500D03*
X369172Y102828D03*
X362000Y123500D03*
Y128000D03*
X376500Y141000D03*
X374000D03*
X360500Y154500D03*
X374900Y154228D03*
X371400Y154300D03*
X367900Y154228D03*
X367400Y174400D03*
X373649Y185735D03*
X377500Y218500D03*
Y221000D03*
Y226500D03*
Y223500D03*
X373500Y247000D03*
X365500Y246500D03*
X375800Y255200D03*
X376500Y269000D03*
X365000Y268000D03*
X370000Y276000D03*
X374500D03*
X361400Y301500D03*
Y305800D03*
Y309900D03*
X365500Y305900D03*
X375500Y309200D03*
X371000Y326000D03*
X370000Y337000D03*
Y332500D03*
X366000Y350850D03*
X360700Y406200D03*
X364500Y413500D03*
X382286Y86214D03*
X379000Y141000D03*
X382000Y142000D03*
X378400Y154300D03*
X384091Y200091D03*
X379500Y237500D03*
X391900Y246800D03*
X386000D03*
X380100D03*
X386000Y259250D03*
X389400Y281100D03*
X378000Y281000D03*
X382200D03*
X394800Y281300D03*
X383000Y323500D03*
X390000Y338500D03*
X392500Y329100D03*
Y323900D03*
X381000Y365000D03*
X386500D03*
X389500Y370000D03*
X395000D03*
Y360000D03*
X383900Y384600D03*
X379500Y381000D03*
Y375800D03*
Y417500D03*
X407500Y225000D03*
X397800Y246800D03*
X403700D03*
X409300D03*
X400000Y265500D03*
X402000Y303000D03*
X396981Y304482D03*
X407500Y300500D03*
X402500Y308000D03*
X408500Y316500D03*
Y321998D03*
Y311000D03*
X398000Y336500D03*
X410000Y338000D03*
X406610Y353410D03*
X411840Y353620D03*
X409000Y371339D03*
X423000Y72950D03*
X417500Y75000D03*
X425000Y87700D03*
X420900Y246800D03*
X415000D03*
X420900Y259000D03*
X424900Y284300D03*
X423900Y278500D03*
X424900Y292900D03*
X413000Y300500D03*
X429442Y310075D03*
X417500Y337000D03*
X422500Y354500D03*
X428500Y346000D03*
X413500Y373500D03*
X419000D03*
X420500Y366000D03*
X425000Y381000D03*
X420500D03*
X423500Y415500D03*
X436500Y233000D03*
X443500Y231500D03*
X436500Y237500D03*
X439500Y250000D03*
X435000Y250500D03*
X443500Y236500D03*
X440000Y278500D03*
X434600Y278300D03*
X435500Y274500D03*
X445600Y278300D03*
X438150Y283800D03*
X447000Y283000D03*
X433050Y291400D03*
X446000Y294000D03*
X439000Y302000D03*
X434500D03*
X433000Y314320D03*
X435143Y306643D03*
X447000Y321998D03*
X440000Y332500D03*
X434000Y328000D03*
X433000Y353500D03*
X433500Y366500D03*
X433382Y360466D03*
X438500Y364500D03*
X438400Y382400D03*
X430000Y381000D03*
X431000Y406500D03*
Y411500D03*
X460000Y76000D03*
X463500Y92000D03*
X458500Y86500D03*
X448500Y100500D03*
X462500Y117000D03*
X461000Y234500D03*
X457500Y227500D03*
Y223500D03*
X449000Y232500D03*
Y227500D03*
X461000Y230000D03*
X448500Y237500D03*
X457500Y250000D03*
X448500D03*
X457500Y237400D03*
X453000Y250000D03*
X457000Y258500D03*
X459500Y262000D03*
X461500Y268409D03*
X460800Y294200D03*
X461000Y302500D03*
X464500Y298500D03*
X456500Y305500D03*
X454000Y312500D03*
X448500Y311500D03*
X461500Y311000D03*
X451000Y306500D03*
X450900Y330900D03*
X450500Y368500D03*
X453500Y381500D03*
X450000Y416500D03*
Y411500D03*
X478000Y78000D03*
X482000Y83500D03*
X465500Y78500D03*
X475500Y82500D03*
X470500D03*
X481000Y172500D03*
X479246Y178464D03*
X477500Y170500D03*
X481500Y193000D03*
X480288Y203788D03*
X471000Y239000D03*
X477000D03*
X468500Y264500D03*
Y270000D03*
X478500Y346000D03*
X481000Y341000D03*
X470500Y391000D03*
X493700Y79161D03*
X496000Y85000D03*
Y163000D03*
X484000Y166000D03*
X497000Y175000D03*
X485033Y174934D03*
X498060Y185500D03*
X483871Y198241D03*
X496500Y197500D03*
X484000Y185500D03*
X497500Y214000D03*
X485000Y202739D03*
X490500Y216750D03*
X492500Y226000D03*
X497500D03*
X497100Y244700D03*
X497200Y240600D03*
X492300Y240800D03*
X497000Y341000D03*
X495000Y346000D03*
X483501D03*
X488500D03*
X504000Y64500D03*
X508500D03*
X513200Y66000D03*
X503005Y99494D03*
X508000Y105500D03*
Y110500D03*
Y115500D03*
X503860Y124150D03*
X503900Y128690D03*
X514500Y144000D03*
X503950Y133500D03*
X514500Y151000D03*
Y148000D03*
Y154000D03*
Y157000D03*
X501500Y192500D03*
X507000D03*
Y188500D03*
X515500Y201000D03*
X513000Y210500D03*
X511500Y206500D03*
X513500Y215500D03*
X509000D03*
X502200Y240700D03*
X501000Y263500D03*
X509000Y340500D03*
X504500D03*
X514000Y374000D03*
X507500Y394500D03*
X503500D03*
X521500Y60000D03*
X529500Y60500D03*
X526500Y67500D03*
X519500Y75500D03*
X533000Y82000D03*
X519500Y81500D03*
X520000Y87000D03*
X524900Y99000D03*
X522500Y114500D03*
X528710Y227500D03*
X534000Y231500D03*
X525400Y247000D03*
X522000D03*
X524300Y261700D03*
X523900Y257100D03*
X523600Y281100D03*
X531000Y285500D03*
X526000Y295500D03*
X519000Y307500D03*
X517500Y374000D03*
X518000Y382500D03*
X527500Y389100D03*
X532100Y399000D03*
X527500Y397100D03*
Y393100D03*
X522100Y416500D03*
X551500Y59597D03*
X549000Y63500D03*
Y78223D03*
X544300Y87100D03*
X549400Y81600D03*
X536500Y84500D03*
Y79000D03*
X543520Y174970D03*
X542270Y169900D03*
X539770Y174900D03*
Y169900D03*
Y172400D03*
X542270D03*
X545800Y216500D03*
X541000Y216400D03*
X537500Y232000D03*
X548300Y222600D03*
X546500Y240500D03*
X541000Y281500D03*
X539500Y292000D03*
X542000Y296450D03*
X537500Y304000D03*
X539000Y370000D03*
X539300Y365100D03*
X539000Y360000D03*
X543000Y370000D03*
X543300Y365100D03*
X543000Y360000D03*
X540600Y386300D03*
X548829Y416329D03*
X548500Y411000D03*
X538558Y413779D03*
X550369Y427558D03*
X538558D03*
X565933Y102000D03*
X562533Y102001D03*
X553000Y108500D03*
X554600Y202400D03*
X558900Y202500D03*
X566950Y220000D03*
X560000Y240000D03*
X565400Y244700D03*
X562000Y254870D03*
X554400Y267500D03*
X561700Y320300D03*
X556700D03*
X562500Y336100D03*
Y326100D03*
X562000Y331600D03*
X560000Y342100D03*
X568100Y366400D03*
Y361700D03*
X568326Y371200D03*
X563800Y390700D03*
X567500Y386500D03*
X568600Y376000D03*
Y380700D03*
X564400Y396700D03*
X567500Y403000D03*
X555000Y402000D03*
X567126Y417500D03*
X555315D03*
X562180Y413779D03*
Y427558D03*
X586500Y107000D03*
Y112500D03*
X571000Y217900D03*
X576500Y219700D03*
X569943Y223300D03*
X585000Y226500D03*
X578900Y236600D03*
X583000Y297000D03*
X580300Y390700D03*
X576900Y403100D03*
X578937Y417500D03*
X572500Y413500D03*
X584000Y421900D03*
X573991Y427558D03*
X588000Y96500D03*
X600850Y112350D03*
X592000Y127063D03*
X599500Y116500D03*
X592000Y141000D03*
Y146000D03*
Y163000D03*
Y151500D03*
Y157063D03*
Y173000D03*
Y178000D03*
Y168000D03*
X587500Y190000D03*
X594003Y187000D03*
X602500Y183000D03*
X601550Y208450D03*
X596450Y210350D03*
X601953Y218853D03*
X590650Y245680D03*
X604000Y254500D03*
X591000Y271500D03*
Y278500D03*
Y291500D03*
X602500Y404000D03*
X591000D03*
X604000Y398000D03*
X597500Y421900D03*
X602559Y417500D03*
X590748Y418725D03*
X597613Y413779D03*
Y427558D03*
X606902Y186000D03*
X610500Y190500D03*
X614100Y236400D03*
X618650Y249300D03*
X609500Y254500D03*
X614500Y398000D03*
Y403500D03*
X614370Y417500D03*
X609424Y413779D03*
Y427558D03*
X633500Y108000D03*
Y102000D03*
Y96500D03*
X637900Y116900D03*
X622000Y127063D03*
Y141500D03*
Y146500D03*
Y162000D03*
Y151600D03*
Y157000D03*
Y181500D03*
Y175500D03*
X622035Y167063D03*
X628500Y189500D03*
X627500Y205374D03*
X633000Y286500D03*
X647000Y108000D03*
G54D20*
X46000Y82000D03*
X51765Y96600D03*
X79500Y234500D03*
X79600Y248900D03*
X77964Y260100D03*
X75800Y274300D03*
X72000Y271400D03*
X82500Y230500D03*
X84600Y248900D03*
X89600D03*
X82500Y273200D03*
X87100Y271300D03*
X112800Y66600D03*
X243500Y48650D03*
X252700Y44000D03*
X297700Y335100D03*
X324000Y236000D03*
X318000Y268500D03*
X324300Y254700D03*
X327500Y232000D03*
X332600Y246600D03*
X328500Y238645D03*
X327800Y246800D03*
X334350Y282000D03*
X336500Y295000D03*
X336525Y320500D03*
Y325500D03*
X341500Y338500D03*
Y328500D03*
Y333500D03*
X336525Y330500D03*
X342900Y246800D03*
X344000Y295000D03*
X358250Y340050D03*
X361124Y349876D03*
X387193Y143005D03*
X391130D03*
X387193Y150879D03*
X391130D03*
X387193Y158753D03*
X391130D03*
X387193Y166627D03*
X391130D03*
X391600Y304800D03*
X379300Y305000D03*
X383000Y328500D03*
Y333500D03*
X395067Y146942D03*
X399005D03*
X395067Y154816D03*
X399005D03*
X395067Y162690D03*
X399005D03*
X402942Y150879D03*
X406879D03*
X395067Y170564D03*
X399005D03*
X402942Y166627D03*
X406879D03*
X421360Y359970D03*
X446248Y143005D03*
Y186311D03*
X442311D03*
X441500Y297500D03*
X444000Y406500D03*
X431900Y392200D03*
X431169Y401169D03*
X444000Y411500D03*
X461996Y131193D03*
X450185Y143005D03*
X465933Y131193D03*
X473807Y135130D03*
Y139067D03*
Y146942D03*
X469870D03*
X470462Y369462D03*
X470500Y395000D03*
X493500Y359000D03*
X503000Y354600D03*
X550643Y400900D03*
X568000Y356700D03*
X555569Y388051D03*
G54D15*
X16039Y71260D03*
Y128346D03*
Y185433D03*
Y242520D03*
G54D21*
X63500Y84500D03*
X56500Y113000D03*
X54500Y171000D03*
X62000Y199500D03*
X57500Y226500D03*
X63600Y291500D03*
X75500Y62000D03*
X64400Y70000D03*
X64500Y129500D03*
X64700Y251700D03*
X79500Y308500D03*
X71000Y330500D03*
X78000D03*
X73500Y357500D03*
X70300D03*
X94500Y299000D03*
X88500Y303000D03*
X95000Y291500D03*
X87500Y295500D03*
X97800Y391800D03*
X99500Y370000D03*
X110500Y382500D03*
X107300D03*
X153500Y310500D03*
X201700Y327900D03*
X229582Y48918D03*
X225000Y396000D03*
X250222Y76300D03*
X247022D03*
X264339Y35300D03*
Y38500D03*
X269907Y76300D03*
X266707D03*
X280087Y35300D03*
Y38500D03*
X285055Y76300D03*
X281855D03*
X295835Y35300D03*
Y38500D03*
Y44900D03*
Y48100D03*
X306500Y169500D03*
X314763Y85237D03*
X312500Y87500D03*
X322710Y190299D03*
X323500Y263000D03*
X324000Y301000D03*
X325910Y190299D03*
X338500Y213500D03*
X330500Y265000D03*
X337500D03*
X332000Y301500D03*
X337000Y344000D03*
X345301Y193099D03*
Y189899D03*
X358000Y261500D03*
X344500Y265000D03*
X370500Y84000D03*
X365700Y92000D03*
X362500D03*
X374600Y178200D03*
X365101Y191559D03*
Y188359D03*
X375000Y210000D03*
X365500Y279500D03*
X369000Y413500D03*
X374500Y418500D03*
X391130Y146942D03*
Y135130D03*
Y162690D03*
Y154816D03*
Y170564D03*
Y182374D03*
Y186311D03*
X385500Y196154D03*
X387193Y186311D03*
X380000Y210000D03*
X391130Y209933D03*
X387193D03*
X394000Y223500D03*
X383000Y232500D03*
X390000D03*
X395000Y382000D03*
X395067Y143005D03*
Y131193D03*
X406879Y135130D03*
X410816D03*
X406879Y139067D03*
X402942D03*
X410811Y131188D03*
X406874D03*
X399000Y135125D03*
Y131188D03*
X395067Y135130D03*
X410816Y143005D03*
Y139067D03*
X406879Y143005D03*
X395067Y158753D03*
X399005Y150879D03*
X402942Y158753D03*
X406879Y162690D03*
Y154816D03*
Y158753D03*
X410816Y170564D03*
X399005Y166627D03*
X402942Y178437D03*
X406879D03*
X395067Y182374D03*
X399005Y186311D03*
Y190248D03*
X402942D03*
X406879Y182374D03*
Y186311D03*
Y194185D03*
X395067Y186311D03*
Y190248D03*
X402942Y182374D03*
X399005Y198122D03*
X395067D03*
X410816Y182374D03*
Y190248D03*
Y198122D03*
X402942Y186311D03*
Y194185D03*
X399005D03*
X402942Y198122D03*
X410816Y194185D03*
X406879Y190248D03*
X395067Y213870D03*
X410816Y205996D03*
X399005Y202059D03*
X395067D03*
X402942Y205996D03*
X399005D03*
X406879Y202059D03*
X410816Y209933D03*
Y202059D03*
X399005Y209933D03*
X395067D03*
X406879Y205996D03*
Y209933D03*
X402942Y202059D03*
X395067Y205996D03*
X406879Y213870D03*
Y217807D03*
X408000Y327000D03*
X420500Y82000D03*
X429000Y123500D03*
X422000D03*
X418500Y117000D03*
X415000Y123500D03*
X418690Y139067D03*
X422627Y135130D03*
X418690D03*
X414753D03*
X422627Y131193D03*
X418690D03*
X426564Y146942D03*
Y143005D03*
Y131193D03*
Y139067D03*
X422627D03*
Y143005D03*
X418690D03*
X414753D03*
Y139067D03*
X418690Y146942D03*
X414753D03*
X418690Y154816D03*
Y162690D03*
X414753Y158753D03*
X422627D03*
X426564Y154816D03*
X414753Y150879D03*
X422627D03*
X418690D03*
X426564D03*
Y178437D03*
X418690Y170564D03*
X414753Y166627D03*
X426564Y170564D03*
X414753Y178437D03*
X422627Y166627D03*
Y178437D03*
X414753Y194185D03*
X426564Y198122D03*
X418690Y182374D03*
X426564Y186311D03*
Y190248D03*
X418690Y198122D03*
X422627Y194185D03*
Y186311D03*
Y182374D03*
X426564D03*
X414753Y190248D03*
X418690D03*
Y186311D03*
X414753D03*
Y182374D03*
Y198122D03*
X426564Y194185D03*
X422627Y198122D03*
X418690Y194185D03*
X422627Y209933D03*
X418690Y205996D03*
X414753D03*
Y209933D03*
X418690Y213870D03*
X414753Y202059D03*
X426564D03*
Y205996D03*
Y209933D03*
X422627Y202059D03*
Y205996D03*
X418690Y209933D03*
X425400Y229600D03*
X420500Y229500D03*
X414900Y229800D03*
X423000Y235400D03*
X416100D03*
X429000Y274000D03*
X434437Y143005D03*
X438374Y131193D03*
X446248Y146942D03*
X442311Y143005D03*
Y146942D03*
X438374Y135130D03*
X434437Y146942D03*
X438374D03*
X446248Y139067D03*
X445939Y135439D03*
X438374Y143005D03*
Y139067D03*
X434437D03*
Y135130D03*
Y131193D03*
Y158753D03*
X442311D03*
X438374Y154816D03*
X446248D03*
Y162690D03*
X434437Y150879D03*
X442311D03*
X446248D03*
X438374Y178437D03*
Y170564D03*
X442311Y166627D03*
X434437Y178437D03*
X446248Y170564D03*
X442311Y178437D03*
X446248Y182374D03*
X438374Y190248D03*
X446248D03*
X434437Y186311D03*
Y190248D03*
Y194185D03*
Y182374D03*
X438374Y198122D03*
X442311Y190248D03*
Y194185D03*
X434437Y198122D03*
X446248D03*
X438374Y182374D03*
Y186311D03*
X446248Y194185D03*
X442311Y198122D03*
X438374Y209933D03*
Y205996D03*
Y202059D03*
X442311Y209933D03*
X438374Y213870D03*
X442311Y202059D03*
X434437D03*
Y213870D03*
X442311Y205996D03*
X446248D03*
Y202059D03*
X434437Y209933D03*
X438374Y217807D03*
X434437D03*
X430000Y386500D03*
X450185Y135130D03*
X461996Y139067D03*
X454122D03*
X458059D03*
X461996Y135130D03*
X454122D03*
X457844Y135345D03*
X449876Y131502D03*
X454122Y131193D03*
X458059Y146942D03*
X461996D03*
X450185D03*
X454122D03*
X458059Y143005D03*
X461996D03*
X450185Y139067D03*
X461996Y162690D03*
X458059Y158753D03*
X454122D03*
Y162690D03*
X450185Y158753D03*
X458059Y150879D03*
Y162690D03*
X454122Y150879D03*
X461996D03*
X454122Y154816D03*
X458059D03*
X461996D03*
X450185Y150879D03*
X458059Y178437D03*
X454122Y166627D03*
X450185D03*
Y178437D03*
X454122D03*
X461996Y170564D03*
Y178437D03*
X458060Y170564D03*
X461996Y166627D03*
X450185Y182374D03*
X458059Y190248D03*
X454122Y182374D03*
X461996D03*
X458059Y194185D03*
X461996Y186311D03*
X458059Y182374D03*
X454122Y194185D03*
X450185D03*
X454122Y190248D03*
X458059Y186311D03*
X454122Y198122D03*
X458059D03*
X461996Y190248D03*
Y198122D03*
Y194185D03*
X450185Y186311D03*
Y190248D03*
X454122Y205996D03*
X461996Y209933D03*
Y205996D03*
Y213870D03*
X458059Y202059D03*
Y205996D03*
X454122Y209933D03*
X458059D03*
X450185D03*
Y213870D03*
X454122D03*
X450185Y202059D03*
X454122D03*
X450185Y205996D03*
X454122Y217807D03*
X450185D03*
X461996D03*
X458059D03*
X479500Y92500D03*
X466500Y110400D03*
X471200Y115700D03*
X481600Y125800D03*
X476800Y120700D03*
X473807Y143005D03*
X465933Y139067D03*
X469870D03*
Y131193D03*
X473807D03*
X465933Y135130D03*
Y143005D03*
X469870D03*
X473807Y154816D03*
X465933Y162690D03*
X473807Y150879D03*
X465933Y154816D03*
X469870D03*
X475000Y163000D03*
X465933Y158753D03*
Y150879D03*
X469870D03*
X465933Y166627D03*
Y170564D03*
Y178437D03*
X469870Y166627D03*
Y170564D03*
X473807D03*
Y178437D03*
X465933Y194185D03*
X473807Y186311D03*
X469870Y198122D03*
X465933Y186311D03*
X469870Y190248D03*
X473807Y182374D03*
X469870D03*
X465933D03*
X469870Y186311D03*
X473807Y190248D03*
X469870Y194185D03*
X465933Y198122D03*
X482000Y212500D03*
X465933Y209933D03*
X469870Y213870D03*
Y209933D03*
X465933Y202059D03*
Y205996D03*
X473807Y213870D03*
X469870Y205996D03*
X473807Y209933D03*
Y217807D03*
X467000Y355500D03*
X482800Y110300D03*
X483000Y133000D03*
X485000Y154000D03*
X497500Y148500D03*
X491000Y154000D03*
X491500Y148500D03*
X497000Y154000D03*
X483100Y272800D03*
X503000Y155000D03*
X503500Y149000D03*
X534500Y253600D03*
X530000Y406500D03*
X544500Y79500D03*
X541000Y96000D03*
X540600Y234600D03*
X558000Y161500D03*
X566000Y347000D03*
X560000Y401000D03*
X580000Y104800D03*
X576500Y98000D03*
X576000Y246500D03*
X571800Y396500D03*
X587000Y184000D03*
X595500Y239000D03*
X619961Y224474D03*
Y227674D03*
G54D19*
X26378Y340080D03*
X28150Y343150D03*
X29922Y340080D03*
X33466D03*
X37010D03*
X40554D03*
X42326Y343150D03*
X38782D03*
X35238D03*
X31694D03*
G54D28*
X605315Y334449D03*
Y350984D03*
Y367519D03*
G54D24*
X126067Y184043D03*
X286067Y104043D03*
G54D31*
X640952Y201181D03*
Y220867D03*
G54D26*
X255906Y309646D03*
Y412008D03*
X494094Y309646D03*
Y412008D03*
G54D11*
X6039Y61260D03*
Y81260D03*
Y118346D03*
Y138346D03*
Y175433D03*
Y195433D03*
Y232520D03*
Y252520D03*
X26039Y61260D03*
Y81260D03*
Y118346D03*
Y138346D03*
Y175433D03*
Y195433D03*
Y232520D03*
Y252520D03*
G54D30*
X651582Y197244D03*
Y224804D03*
G54D23*
X126067Y104043D03*
Y264043D03*
X253967Y93443D03*
X265967D03*
X277867D03*
X286067Y264043D03*
G54D13*
X29528Y36811D03*
Y373031D03*
X640039Y65354D03*
Y417835D03*
G54D25*
X143567Y106043D03*
X146067Y268043D03*
X268567Y112143D03*
Y255943D03*
G54D29*
X634055Y334449D03*
Y367519D03*
G54D18*
X22834Y340080D03*
X24606Y343150D03*
X44098Y340080D03*
X45870Y343150D03*
G54D27*
X588779Y334449D03*
Y350984D03*
Y367519D03*
%LPC*%
G75*
G54D10*
X8878Y21717D03*
X4878D03*
X4000Y25619D03*
Y29619D03*
Y33619D03*
Y37619D03*
Y41619D03*
Y45619D03*
Y49619D03*
Y281619D03*
Y285619D03*
Y289619D03*
Y293619D03*
Y297619D03*
Y301619D03*
Y305619D03*
Y309619D03*
Y313619D03*
Y337619D03*
Y341619D03*
Y345619D03*
Y349619D03*
Y353619D03*
Y357619D03*
Y361619D03*
Y365619D03*
Y369619D03*
Y373619D03*
Y377619D03*
Y381619D03*
Y385619D03*
Y389619D03*
Y393619D03*
Y397619D03*
Y401619D03*
Y405619D03*
Y409619D03*
Y413619D03*
Y417619D03*
Y421619D03*
Y425619D03*
Y429619D03*
X4413Y433598D03*
X8413D03*
X24878Y21717D03*
X20878D03*
X16878D03*
X12878D03*
X12413Y433598D03*
X16413D03*
X20413D03*
X24413D03*
X28413D03*
X44878Y21717D03*
X40878D03*
X36878D03*
X32878D03*
X28878D03*
X32413Y433598D03*
X36413D03*
X40413D03*
X44413D03*
X55055Y25073D03*
X52878Y21717D03*
X48878D03*
X55055Y41073D03*
Y37073D03*
Y33073D03*
Y29073D03*
X61463Y54048D03*
X57859Y52313D03*
X55558Y49041D03*
X55055Y45073D03*
X48413Y433598D03*
X52413D03*
X56413D03*
X60413D03*
X77460Y54197D03*
X73460D03*
X69460D03*
X65460D03*
X79248Y266100D03*
X67000Y283100D03*
X76700Y357500D03*
X67100D03*
X68413Y433598D03*
X72413D03*
X76413D03*
X80413D03*
X64413D03*
X97460Y54197D03*
X93460D03*
X89460D03*
X85460D03*
X81460D03*
X86800Y230000D03*
X85600Y263700D03*
X85800Y287452D03*
X84413Y433598D03*
X88413D03*
X92413D03*
X96413D03*
X113460Y54197D03*
X109460D03*
X105460D03*
X101460D03*
X113700Y382500D03*
X104100D03*
X104413Y433598D03*
X108413D03*
X112413D03*
X100413D03*
X132920Y51926D03*
X129450Y53917D03*
X125460Y54197D03*
X121460D03*
X117460D03*
X116413Y433598D03*
X120413D03*
X124413D03*
X128413D03*
X132413D03*
X135299Y24509D03*
X150163Y21717D03*
X146163D03*
X142163D03*
X138163D03*
X135299Y28509D03*
Y32509D03*
Y36509D03*
Y40509D03*
Y44509D03*
X134977Y48496D03*
X144000Y62500D03*
X138500Y75000D03*
X140413Y433598D03*
X144413D03*
X148413D03*
X136413D03*
X158163Y21717D03*
X154163D03*
X158795Y25667D03*
Y41667D03*
Y37667D03*
Y33667D03*
Y29667D03*
X160736Y49309D03*
X159112Y45654D03*
X163543Y52159D03*
X151840Y79935D03*
X167100Y405600D03*
X152413Y433598D03*
X156413D03*
X160413D03*
X164413D03*
X180341Y47225D03*
X178196Y50601D03*
X168413Y433598D03*
X172413D03*
X176413D03*
X180413D03*
X184413D03*
X191535Y28900D03*
X201950Y29050D03*
X200413Y433598D03*
X188413D03*
X192413D03*
X196413D03*
X208300Y289500D03*
X217300D03*
X209660Y331500D03*
X204413Y433598D03*
X208413D03*
X212413D03*
X216413D03*
X220413D03*
X232700Y29100D03*
X221800Y289500D03*
X224413Y433598D03*
X228413D03*
X232413D03*
X236413D03*
X254527Y28900D03*
X244619D03*
X240508Y76300D03*
Y66700D03*
X243822Y76300D03*
X253422D03*
X240413Y433598D03*
X244413D03*
X248413D03*
X252413D03*
X264339Y32100D03*
X264304Y28900D03*
X272309D03*
X264339Y41700D03*
X263507Y76300D03*
X256413Y433598D03*
X260413D03*
X264413D03*
X268413D03*
X272413D03*
X280087Y41700D03*
Y32100D03*
X280052Y28900D03*
X288057D03*
X288255Y76300D03*
X273107D03*
X278655D03*
X284500Y181100D03*
X277000Y198700D03*
X286600D03*
X284500Y190700D03*
X286151Y329500D03*
X288413Y433598D03*
X284413D03*
X280413D03*
X276413D03*
X295835Y41700D03*
Y32100D03*
X295800Y28900D03*
X298726Y43529D03*
Y49471D03*
X304413Y433598D03*
X300413D03*
X296413D03*
X292413D03*
X307708Y28900D03*
X321402Y54197D03*
X317402D03*
X310237Y89763D03*
X317025Y82975D03*
X319510Y190299D03*
X322200Y325000D03*
X310600Y330500D03*
X324413Y433598D03*
X320413D03*
X316413D03*
X312413D03*
X308413D03*
X329402Y54197D03*
X325402D03*
X337402D03*
X341402D03*
X333402D03*
X338599Y108500D03*
X337500Y113000D03*
Y122600D03*
X329110Y190299D03*
X340413Y433598D03*
X336413D03*
X332413D03*
X328413D03*
X345402Y54197D03*
X349402D03*
X353402D03*
X357402D03*
X359300Y92000D03*
X348199Y108500D03*
X348264Y104707D03*
X357864D03*
X345301Y196299D03*
Y186699D03*
X354850Y276100D03*
X354800Y289800D03*
X355000Y332500D03*
X356413Y433598D03*
X352413D03*
X348413D03*
X344413D03*
X369402Y54197D03*
X373402D03*
X377402D03*
X361402D03*
X365402D03*
X373500Y78000D03*
X368900Y92000D03*
X373500Y94000D03*
X365101Y194759D03*
Y185159D03*
X376413Y433598D03*
X372413D03*
X368413D03*
X364413D03*
X360413D03*
X381402Y54197D03*
X385402D03*
X389402D03*
X393402D03*
X379500Y72500D03*
X380500Y77400D03*
X390000Y100500D03*
X387193Y135130D03*
X391130Y139067D03*
X387193D03*
Y146942D03*
Y154816D03*
Y162690D03*
Y170564D03*
X391130Y178437D03*
X387193D03*
X391130Y205996D03*
X387193Y217807D03*
X392413Y433598D03*
X388413D03*
X384413D03*
X380413D03*
X397402Y54197D03*
X401402D03*
X405402D03*
X409402D03*
X396400Y100500D03*
X409200D03*
X398450Y116099D03*
X408050D03*
X395067Y139067D03*
X399005D03*
Y143005D03*
X402942D03*
Y146942D03*
X406879D03*
X410816D03*
X395067Y150879D03*
X402942Y154816D03*
X399005Y158753D03*
X410816D03*
X402942Y162690D03*
X410816D03*
Y150879D03*
Y154816D03*
X395067Y166627D03*
X410816D03*
X402942Y170564D03*
X406879D03*
X395067Y178437D03*
X399005D03*
X410816D03*
X406879Y198122D03*
X399005Y182374D03*
X410816Y186311D03*
X395067Y194185D03*
X402942Y209933D03*
X408413Y433598D03*
X404413D03*
X400413D03*
X396413D03*
X417402Y54197D03*
X421402D03*
X425402D03*
X429402D03*
X413402D03*
X413622Y75000D03*
X414753Y131193D03*
X422627Y146942D03*
X426564Y135130D03*
X414753Y162690D03*
Y154816D03*
X418690Y158753D03*
X422627Y162690D03*
Y154816D03*
X426564Y162690D03*
Y158753D03*
X418690Y166627D03*
X414753Y170564D03*
X422627D03*
X418690Y178437D03*
X426564Y166627D03*
X422627Y190248D03*
X414753Y213870D03*
X418690Y202059D03*
X426564Y217807D03*
X428413Y433598D03*
X424413D03*
X420413D03*
X416413D03*
X412413D03*
X433402Y54197D03*
X437402D03*
X441402D03*
X445402D03*
X444050Y116599D03*
X434450D03*
X442311Y139067D03*
X446248Y158753D03*
X442311Y162690D03*
X434437D03*
Y154816D03*
X438374Y162690D03*
Y150879D03*
Y158753D03*
X442311Y154816D03*
X438374Y166627D03*
X446248D03*
X434437Y170564D03*
X442311D03*
X446248Y178437D03*
X434437Y166627D03*
X442311Y182374D03*
X438374Y194185D03*
X434437Y205996D03*
X446248Y209933D03*
X446500Y289500D03*
X439500Y337892D03*
X443000Y401500D03*
Y396500D03*
X444000Y416500D03*
X444413Y433598D03*
X440413D03*
X436413D03*
X432413D03*
X449402Y54197D03*
X453402D03*
X457402D03*
X461402D03*
X450930Y122167D03*
X460530D03*
X454122Y143005D03*
X457844Y131408D03*
X450185Y154816D03*
X461996Y158753D03*
X450185Y162690D03*
X458059Y166627D03*
X450185Y170564D03*
X454123D03*
X454122Y186311D03*
X450185Y198122D03*
X461996Y202059D03*
X458059Y213870D03*
X464413Y433598D03*
X460413D03*
X456413D03*
X452413D03*
X448413D03*
X465402Y54197D03*
X469402D03*
X473402D03*
X477402D03*
X481402D03*
X465933Y146942D03*
X469870Y135130D03*
Y178437D03*
X473807Y166627D03*
X465933Y190248D03*
X473807Y205996D03*
X469870Y217807D03*
X480413Y433598D03*
X476413D03*
X472413D03*
X468413D03*
X485402Y54197D03*
X489402D03*
X493402D03*
X497402D03*
X496413Y433598D03*
X492413D03*
X488413D03*
X484413D03*
X501402Y54197D03*
X505402D03*
X509402D03*
X513402D03*
X516413Y433598D03*
X512413D03*
X508413D03*
X504413D03*
X500413D03*
X517402Y54197D03*
X521402D03*
X525402D03*
X529402D03*
X533402D03*
X532413Y433598D03*
X528413D03*
X524413D03*
X520413D03*
X537402Y54197D03*
X541402D03*
X545402D03*
X549402D03*
X548413Y433598D03*
X544413D03*
X540413D03*
X536413D03*
X553402Y54197D03*
X557402D03*
X561402D03*
X565402D03*
X566600Y212900D03*
X568413Y433598D03*
X564413D03*
X560413D03*
X556413D03*
X552413D03*
X569402Y54197D03*
X573402D03*
X577402D03*
X581402D03*
X585402D03*
X584413Y433598D03*
X580413D03*
X576413D03*
X572413D03*
X589402Y54197D03*
X593402D03*
X597402D03*
X601402D03*
X600413Y433598D03*
X596413D03*
X592413D03*
X588413D03*
X605402Y54197D03*
X609402D03*
X613402D03*
X617402D03*
X621402D03*
X619961Y230874D03*
Y221274D03*
X620413Y433598D03*
X616413D03*
X612413D03*
X608413D03*
X604413D03*
X625402Y54197D03*
X629402D03*
X636413Y433598D03*
X632413D03*
X628413D03*
X624413D03*
X649402Y54197D03*
X653402D03*
X656039Y57205D03*
Y61205D03*
Y65205D03*
Y69205D03*
Y73205D03*
Y77205D03*
Y81205D03*
Y85205D03*
Y89205D03*
Y93205D03*
Y97205D03*
Y101205D03*
Y105205D03*
Y109205D03*
Y113205D03*
Y117205D03*
Y121205D03*
Y125205D03*
Y129205D03*
Y145205D03*
Y133205D03*
Y137205D03*
Y141205D03*
Y149205D03*
Y153205D03*
Y157205D03*
Y161205D03*
Y165205D03*
Y169205D03*
Y173205D03*
Y177205D03*
Y181205D03*
Y235585D03*
Y311909D03*
Y315909D03*
Y319909D03*
Y323909D03*
Y327909D03*
Y331909D03*
Y335909D03*
Y339909D03*
Y343909D03*
Y347909D03*
Y351909D03*
Y355909D03*
Y359909D03*
Y363909D03*
Y367909D03*
Y371909D03*
Y375909D03*
Y379909D03*
Y383909D03*
Y387909D03*
Y391909D03*
Y395909D03*
Y399909D03*
Y403909D03*
Y407909D03*
Y411909D03*
Y415909D03*
Y419909D03*
Y423909D03*
Y427909D03*
Y431909D03*
X652413Y433598D03*
X648413D03*
X644413D03*
X640413D03*
G54D32*
G01X136000Y-65500D02*
Y-158000D01*
X506000D01*
Y-65500D01*
X136000D01*
G01X316000D02*
Y-158000D01*
G54D14*
X19878Y36811D03*
X22704Y29987D03*
Y43635D03*
X19878Y373031D03*
X22704Y366207D03*
Y379855D03*
X29528Y27161D03*
X36352Y29987D03*
X39178Y36811D03*
X36352Y43635D03*
X29528Y46461D03*
Y363381D03*
X36352Y366207D03*
X39178Y373031D03*
X36352Y379855D03*
X29528Y382681D03*
X633215Y58530D03*
Y72178D03*
X630389Y65354D03*
X633215Y424659D03*
X630389Y417835D03*
X633215Y411011D03*
X640039Y55704D03*
X646863Y58530D03*
X649689Y65354D03*
X646863Y72178D03*
X640039Y75004D03*
Y408185D03*
X646863Y411011D03*
X649689Y417835D03*
X646863Y424659D03*
X640039Y427485D03*
G54D33*
G01X329433Y-125500D02*
Y-133000D01*
X333167D01*
G01X340480D02*
Y-128000D01*
G01Y-128875D02*
X340107Y-128375D01*
X339547Y-128125D01*
X338893Y-128000D01*
X338240Y-128250D01*
X337680Y-128750D01*
X337307Y-129500D01*
X337120Y-130500D01*
X337307Y-131500D01*
X337680Y-132250D01*
X338240Y-132750D01*
X338893Y-133000D01*
X339547Y-132875D01*
X340107Y-132500D01*
X340480Y-132000D01*
G01X344340Y-135250D02*
X344900Y-135500D01*
X345647Y-135250D01*
X346113Y-134750D01*
X346487Y-134125D01*
X347047Y-132125D01*
X348260Y-128000D01*
G01X345273D02*
X347047Y-132125D01*
G01X352400Y-129625D02*
X355387D01*
X355107Y-128750D01*
X354640Y-128250D01*
X353987Y-128000D01*
X353333Y-128125D01*
X352773Y-128500D01*
X352400Y-129375D01*
X352213Y-130125D01*
Y-130875D01*
X352400Y-131625D01*
X352867Y-132375D01*
X353427Y-132875D01*
X354080Y-133000D01*
X354733Y-132750D01*
X355387Y-132000D01*
G01X359993Y-133000D02*
Y-128000D01*
G01Y-129000D02*
X360460Y-128500D01*
X360927Y-128125D01*
X361580Y-128000D01*
X362047Y-128125D01*
X362607Y-128500D01*
G01X368800Y-133250D02*
X368613Y-133125D01*
Y-132875D01*
X368800Y-132750D01*
X368987Y-132875D01*
Y-133125D01*
X368800Y-133250D01*
G01Y-129875D02*
X368613Y-129750D01*
Y-129500D01*
X368800Y-129375D01*
X368987Y-129500D01*
Y-129750D01*
X368800Y-129875D01*
G01X336747Y-120500D02*
Y-113000D01*
X338613D01*
X339360Y-113375D01*
X339920Y-113875D01*
X340387Y-114625D01*
X340760Y-115500D01*
X340853Y-116750D01*
X340760Y-118000D01*
X340387Y-118875D01*
X339920Y-119625D01*
X339360Y-120125D01*
X338613Y-120500D01*
X336747D01*
G01X347980D02*
Y-115500D01*
G01Y-116375D02*
X347607Y-115875D01*
X347047Y-115625D01*
X346393Y-115500D01*
X345740Y-115750D01*
X345180Y-116250D01*
X344807Y-117000D01*
X344620Y-118000D01*
X344807Y-119000D01*
X345180Y-119750D01*
X345740Y-120250D01*
X346393Y-120500D01*
X347047Y-120375D01*
X347607Y-120000D01*
X347980Y-119500D01*
G01X353800Y-113000D02*
Y-120500D01*
G01X352493Y-115500D02*
X355107D01*
G01X359900Y-117125D02*
X362887D01*
X362607Y-116250D01*
X362140Y-115750D01*
X361487Y-115500D01*
X360833Y-115625D01*
X360273Y-116000D01*
X359900Y-116875D01*
X359713Y-117625D01*
Y-118375D01*
X359900Y-119125D01*
X360367Y-119875D01*
X360927Y-120375D01*
X361580Y-120500D01*
X362233Y-120250D01*
X362887Y-119500D01*
G01X368800Y-120750D02*
X368613Y-120625D01*
Y-120375D01*
X368800Y-120250D01*
X368987Y-120375D01*
Y-120625D01*
X368800Y-120750D01*
G01Y-117375D02*
X368613Y-117250D01*
Y-117000D01*
X368800Y-116875D01*
X368987Y-117000D01*
Y-117250D01*
X368800Y-117375D01*
G01X382027Y-114250D02*
X382587Y-113500D01*
X383240Y-113125D01*
X383987Y-113000D01*
X384920Y-113250D01*
X385573Y-113875D01*
X385760Y-114625D01*
X385667Y-115375D01*
X385293Y-116000D01*
X383427Y-117250D01*
X382587Y-118125D01*
X382027Y-119375D01*
X381840Y-120500D01*
X385760D01*
G01X391300Y-113000D02*
X390553Y-113250D01*
X389993Y-113875D01*
X389620Y-114625D01*
X389340Y-115625D01*
X389247Y-116750D01*
X389340Y-117875D01*
X389620Y-118875D01*
X389993Y-119625D01*
X390553Y-120250D01*
X391300Y-120500D01*
X392047Y-120250D01*
X392607Y-119625D01*
X392980Y-118875D01*
X393260Y-117875D01*
X393353Y-116750D01*
X393260Y-115625D01*
X392980Y-114625D01*
X392607Y-113875D01*
X392047Y-113250D01*
X391300Y-113000D01*
G01X397027Y-114250D02*
X397587Y-113500D01*
X398240Y-113125D01*
X398987Y-113000D01*
X399920Y-113250D01*
X400573Y-113875D01*
X400760Y-114625D01*
X400667Y-115375D01*
X400293Y-116000D01*
X398427Y-117250D01*
X397587Y-118125D01*
X397027Y-119375D01*
X396840Y-120500D01*
X400760D01*
G01X404527Y-114250D02*
X405087Y-113500D01*
X405740Y-113125D01*
X406487Y-113000D01*
X407420Y-113250D01*
X408073Y-113875D01*
X408260Y-114625D01*
X408167Y-115375D01*
X407793Y-116000D01*
X405927Y-117250D01*
X405087Y-118125D01*
X404527Y-119375D01*
X404340Y-120500D01*
X408260D01*
G01X412587Y-118000D02*
X415013D01*
G01X421300Y-113000D02*
X420553Y-113250D01*
X419993Y-113875D01*
X419620Y-114625D01*
X419340Y-115625D01*
X419247Y-116750D01*
X419340Y-117875D01*
X419620Y-118875D01*
X419993Y-119625D01*
X420553Y-120250D01*
X421300Y-120500D01*
X422047Y-120250D01*
X422607Y-119625D01*
X422980Y-118875D01*
X423260Y-117875D01*
X423353Y-116750D01*
X423260Y-115625D01*
X422980Y-114625D01*
X422607Y-113875D01*
X422047Y-113250D01*
X421300Y-113000D01*
G01X427027Y-114250D02*
X427587Y-113500D01*
X428240Y-113125D01*
X428987Y-113000D01*
X429920Y-113250D01*
X430573Y-113875D01*
X430760Y-114625D01*
X430667Y-115375D01*
X430293Y-116000D01*
X428427Y-117250D01*
X427587Y-118125D01*
X427027Y-119375D01*
X426840Y-120500D01*
X430760D01*
G01X435087Y-118000D02*
X437513D01*
G01X442027Y-114250D02*
X442587Y-113500D01*
X443240Y-113125D01*
X443987Y-113000D01*
X444920Y-113250D01*
X445573Y-113875D01*
X445760Y-114625D01*
X445667Y-115375D01*
X445293Y-116000D01*
X443427Y-117250D01*
X442587Y-118125D01*
X442027Y-119375D01*
X441840Y-120500D01*
X445760D01*
G01X449247Y-119375D02*
X449807Y-120000D01*
X450460Y-120375D01*
X451300Y-120500D01*
X452140Y-120250D01*
X452793Y-119750D01*
X453260Y-118875D01*
X453353Y-117875D01*
X453167Y-116875D01*
X452700Y-116250D01*
X452047Y-115750D01*
X451393Y-115625D01*
X450740Y-115750D01*
X449900Y-116250D01*
X450180Y-113000D01*
X452700D01*
G01X336933Y-108000D02*
Y-100500D01*
X339267D01*
X340013Y-100875D01*
X340480Y-101375D01*
X340667Y-102375D01*
X340480Y-103375D01*
X339920Y-104000D01*
X339267Y-104375D01*
X336933D01*
G01X339267D02*
X340667Y-108000D01*
G01X344900Y-104625D02*
X347887D01*
X347607Y-103750D01*
X347140Y-103250D01*
X346487Y-103000D01*
X345833Y-103125D01*
X345273Y-103500D01*
X344900Y-104375D01*
X344713Y-105125D01*
Y-105875D01*
X344900Y-106625D01*
X345367Y-107375D01*
X345927Y-107875D01*
X346580Y-108000D01*
X347233Y-107750D01*
X347887Y-107000D01*
G01X352120Y-103000D02*
X353800Y-108000D01*
X355480Y-103000D01*
G01X368800Y-108250D02*
X368613Y-108125D01*
Y-107875D01*
X368800Y-107750D01*
X368987Y-107875D01*
Y-108125D01*
X368800Y-108250D01*
G01Y-104875D02*
X368613Y-104750D01*
Y-104500D01*
X368800Y-104375D01*
X368987Y-104500D01*
Y-104750D01*
X368800Y-104875D01*
G01X383800Y-100500D02*
X383053Y-100750D01*
X382493Y-101375D01*
X382120Y-102125D01*
X381840Y-103125D01*
X381747Y-104250D01*
X381840Y-105375D01*
X382120Y-106375D01*
X382493Y-107125D01*
X383053Y-107750D01*
X383800Y-108000D01*
X384547Y-107750D01*
X385107Y-107125D01*
X385480Y-106375D01*
X385760Y-105375D01*
X385853Y-104250D01*
X385760Y-103125D01*
X385480Y-102125D01*
X385107Y-101375D01*
X384547Y-100750D01*
X383800Y-100500D01*
G01X391300Y-108000D02*
Y-100500D01*
X390180Y-102000D01*
G01Y-108000D02*
X392420D01*
G01X336933Y-95500D02*
Y-88000D01*
X339173D01*
X339920Y-88375D01*
X340480Y-89250D01*
X340667Y-90250D01*
X340480Y-91250D01*
X340013Y-92000D01*
X339173Y-92375D01*
X336933D01*
G01X344620Y-95750D02*
X347980Y-88000D01*
G01X351653Y-95500D02*
Y-88000D01*
X355947Y-95500D01*
Y-88000D01*
G01X368800Y-95750D02*
X368613Y-95625D01*
Y-95375D01*
X368800Y-95250D01*
X368987Y-95375D01*
Y-95625D01*
X368800Y-95750D01*
G01Y-92375D02*
X368613Y-92250D01*
Y-92000D01*
X368800Y-91875D01*
X368987Y-92000D01*
Y-92250D01*
X368800Y-92375D01*
G01X381933Y-95500D02*
Y-88000D01*
X384267D01*
X385013Y-88375D01*
X385480Y-88875D01*
X385667Y-89875D01*
X385480Y-90875D01*
X384920Y-91500D01*
X384267Y-91875D01*
X381933D01*
G01X384267D02*
X385667Y-95500D01*
G01X392420D02*
Y-88000D01*
X388967Y-93375D01*
X393633D01*
G01X398800Y-88000D02*
X398053Y-88250D01*
X397493Y-88875D01*
X397120Y-89625D01*
X396840Y-90625D01*
X396747Y-91750D01*
X396840Y-92875D01*
X397120Y-93875D01*
X397493Y-94625D01*
X398053Y-95250D01*
X398800Y-95500D01*
X399547Y-95250D01*
X400107Y-94625D01*
X400480Y-93875D01*
X400760Y-92875D01*
X400853Y-91750D01*
X400760Y-90625D01*
X400480Y-89625D01*
X400107Y-88875D01*
X399547Y-88250D01*
X398800Y-88000D01*
G01X406300D02*
X405553Y-88250D01*
X404993Y-88875D01*
X404620Y-89625D01*
X404340Y-90625D01*
X404247Y-91750D01*
X404340Y-92875D01*
X404620Y-93875D01*
X404993Y-94625D01*
X405553Y-95250D01*
X406300Y-95500D01*
X407047Y-95250D01*
X407607Y-94625D01*
X407980Y-93875D01*
X408260Y-92875D01*
X408353Y-91750D01*
X408260Y-90625D01*
X407980Y-89625D01*
X407607Y-88875D01*
X407047Y-88250D01*
X406300Y-88000D01*
G01X412027Y-92375D02*
X412680Y-91500D01*
X413240Y-91000D01*
X413987Y-90750D01*
X414640Y-91000D01*
X415107Y-91500D01*
X415480Y-92250D01*
X415573Y-93125D01*
X415480Y-93875D01*
X415107Y-94625D01*
X414547Y-95250D01*
X413893Y-95500D01*
X413147Y-95250D01*
X412493Y-94500D01*
X412120Y-93375D01*
X412027Y-92125D01*
X412213Y-90500D01*
X412493Y-89625D01*
X412960Y-88750D01*
X413613Y-88125D01*
X414267Y-88000D01*
X414920Y-88250D01*
X415387Y-88875D01*
G01X420087Y-93000D02*
X422513D01*
G01X429547Y-91500D02*
X429920Y-91125D01*
X430200Y-90500D01*
X430387Y-89625D01*
X430200Y-88875D01*
X429827Y-88375D01*
X429173Y-88000D01*
X426653D01*
Y-95500D01*
X429733D01*
X430387Y-95000D01*
X430760Y-94250D01*
X430947Y-93375D01*
X430760Y-92500D01*
X430200Y-91750D01*
X429547Y-91500D01*
X426653D01*
G01X436300Y-88000D02*
X435553Y-88250D01*
X434993Y-88875D01*
X434620Y-89625D01*
X434340Y-90625D01*
X434247Y-91750D01*
X434340Y-92875D01*
X434620Y-93875D01*
X434993Y-94625D01*
X435553Y-95250D01*
X436300Y-95500D01*
X437047Y-95250D01*
X437607Y-94625D01*
X437980Y-93875D01*
X438260Y-92875D01*
X438353Y-91750D01*
X438260Y-90625D01*
X437980Y-89625D01*
X437607Y-88875D01*
X437047Y-88250D01*
X436300Y-88000D01*
G01X443800D02*
X443053Y-88250D01*
X442493Y-88875D01*
X442120Y-89625D01*
X441840Y-90625D01*
X441747Y-91750D01*
X441840Y-92875D01*
X442120Y-93875D01*
X442493Y-94625D01*
X443053Y-95250D01*
X443800Y-95500D01*
X444547Y-95250D01*
X445107Y-94625D01*
X445480Y-93875D01*
X445760Y-92875D01*
X445853Y-91750D01*
X445760Y-90625D01*
X445480Y-89625D01*
X445107Y-88875D01*
X444547Y-88250D01*
X443800Y-88000D01*
G01X451300D02*
X450553Y-88250D01*
X449993Y-88875D01*
X449620Y-89625D01*
X449340Y-90625D01*
X449247Y-91750D01*
X449340Y-92875D01*
X449620Y-93875D01*
X449993Y-94625D01*
X450553Y-95250D01*
X451300Y-95500D01*
X452047Y-95250D01*
X452607Y-94625D01*
X452980Y-93875D01*
X453260Y-92875D01*
X453353Y-91750D01*
X453260Y-90625D01*
X452980Y-89625D01*
X452607Y-88875D01*
X452047Y-88250D01*
X451300Y-88000D01*
G01X458800Y-95500D02*
Y-88000D01*
X457680Y-89500D01*
G01Y-95500D02*
X459920D01*
G01X465087Y-93000D02*
X467513D01*
G01X473800Y-88000D02*
X473053Y-88250D01*
X472493Y-88875D01*
X472120Y-89625D01*
X471840Y-90625D01*
X471747Y-91750D01*
X471840Y-92875D01*
X472120Y-93875D01*
X472493Y-94625D01*
X473053Y-95250D01*
X473800Y-95500D01*
X474547Y-95250D01*
X475107Y-94625D01*
X475480Y-93875D01*
X475760Y-92875D01*
X475853Y-91750D01*
X475760Y-90625D01*
X475480Y-89625D01*
X475107Y-88875D01*
X474547Y-88250D01*
X473800Y-88000D01*
G01X479527Y-89250D02*
X480087Y-88500D01*
X480740Y-88125D01*
X481487Y-88000D01*
X482420Y-88250D01*
X483073Y-88875D01*
X483260Y-89625D01*
X483167Y-90375D01*
X482793Y-91000D01*
X480927Y-92250D01*
X480087Y-93125D01*
X479527Y-94375D01*
X479340Y-95500D01*
X483260D01*
G54D34*
G01X145964Y-110118D02*
G03I-634J0D01*
G01X149695D02*
G03I-1038J0D01*
G01X168013Y-137456D02*
G03I-634J0D01*
G01X155900Y-133655D02*
G03I-632J0D01*
G01X161735Y-128639D02*
G03I-1458J0D01*
G01X158530Y-131428D02*
G03I-1041J0D01*
G01X158461Y-119126D02*
G03I-1283J0D01*
G01X162690Y-117490D02*
G03I-1584J0D01*
G01X169809Y-121292D02*
G03I-2180J0D01*
G01X165531Y-125255D02*
G03I-1869J0D01*
G01X167813Y-115513D02*
G03I-1971J0D01*
G01X154775Y-120500D02*
G03I-892J0D01*
G01X162681Y-102774D02*
G03I-1584J0D01*
G01X158451Y-101149D02*
G03I-1283J0D01*
G01X159258Y-110118D02*
G03I-1868J0D01*
G01X169812Y-98951D02*
G03I-2180J0D01*
G01X167802Y-104739D02*
G03I-1971J0D01*
G01X165183Y-110118D02*
G03I-2180J0D01*
G01X171881D02*
G03I-2642J0D01*
G01X152135Y-98681D02*
G03I-632J0D01*
G01X154064Y-110118D02*
G03I-1460J0D01*
G01X154764Y-99775D02*
G03I-892J0D01*
G01X158530Y-88809D02*
G03I-1041J0D01*
G01X161742Y-91601D02*
G03I-1458J0D01*
G01X165531Y-94981D02*
G03I-1869J0D01*
G01X171080Y-131739D02*
G03I-1282J0D01*
G01X169322Y-135033D02*
G03I-892J0D01*
G01X180669Y-131528D02*
G03I-1870J0D01*
G01X180255Y-136311D02*
G03I-1456J0D01*
G01X179841Y-140261D02*
G03I-1042J0D01*
G01X179433Y-143587D02*
G03I-634J0D01*
G01X181439Y-119680D02*
G03I-2640J0D01*
G01X175373Y-123081D02*
G03I-1968J0D01*
G01X173018Y-127816D02*
G03I-1584J0D01*
G01X174681Y-116876D02*
G03I-2640J0D01*
G01X180979Y-125917D02*
G03I-2180J0D01*
G01X186177Y-123075D02*
G03I-1971J0D01*
G01X188199Y-116876D02*
G03I-2640J0D01*
G01X175452Y-97124D02*
G03I-1968J0D01*
G01X186225Y-97178D02*
G03I-1971J0D01*
G01X181439Y-100556D02*
G03I-2640J0D01*
G01X174681Y-103361D02*
G03I-2640J0D01*
G01X188199D02*
G03I-2640J0D01*
G01X179841Y-79975D02*
G03I-1042J0D01*
G01X171217Y-88444D02*
G03I-1282J0D01*
G01X173123Y-92378D02*
G03I-1584J0D01*
G01X180255Y-83924D02*
G03I-1456J0D01*
G01X180669Y-88708D02*
G03I-1870J0D01*
G01X180979Y-94320D02*
G03I-2180J0D01*
G01X179433Y-76648D02*
G03I-634J0D01*
G01X191096Y-134658D02*
G03I-892J0D01*
G01X192135Y-136781D02*
G03I-631J0D01*
G01X198775Y-128635D02*
G03I-1458J0D01*
G01X195808Y-125255D02*
G03I-1869J0D01*
G01X200547Y-113952D02*
G03X203345Y-117196I7247J3422D01*
G01X192148Y-121285D02*
G03I-2180J0D01*
G01X187928Y-127802D02*
G03I-1584J0D01*
G01X189667Y-131511D02*
G03I-1283J0D01*
G01X200699Y-105836D02*
G03X200547Y-113953I8974J-4228D01*
G01X208284Y-101612D02*
G03X200698Y-105835I-219J-8531D01*
G01X192148Y-98951D02*
G03I-2180J0D01*
G01X191108Y-82727D02*
G03I-634J0D01*
G01X190184Y-85250D02*
G03I-893J0D01*
G01X195808Y-94981D02*
G03I-1869J0D01*
G01X187839Y-92457D02*
G03I-1584J0D01*
G01X189190Y-88538D02*
G03I-1283J0D01*
G01X214259Y-115661D02*
G03X213314Y-114453I-714J415D01*
G01X202049Y-108260D02*
G03X205722Y-116181I7039J-1548D01*
G01X218075Y-112869D02*
G03X219083Y-115752I4343J-99D01*
G01X208854Y-116658D02*
G03X213313Y-114452I-2485J10632D01*
G01X208470Y-118462D02*
G03X214261Y-115663I-1122J9711D01*
G01X203346Y-117195D02*
G03X208470Y-118461I4545J7394D01*
G01X205721Y-116179D02*
G03X208853Y-116659I2561J6250D01*
G01X215903Y-114020D02*
G03X219079Y-118061I6190J1597D01*
G01X215904Y-114020D02*
Y-111835D01*
G01X227413Y-112869D02*
X218074D01*
G01X214175Y-103951D02*
G03X208283Y-101613I-6403J-7542D01*
G01X213150Y-105147D02*
G03X214175Y-103951I410J686D01*
G01X213152Y-105146D02*
G03X208030Y-103430I-5122J-6786D01*
G01X208029Y-103429D02*
G03X202049Y-108259I-48J-6058D01*
G01X225189Y-111399D02*
G03X218071I-3559J159D01*
G01X218070Y-111418D02*
Y-111399D01*
G01X225188Y-111418D02*
X218070D01*
G01X227412Y-111835D02*
G03X215906I-5753J223D01*
G01X230059Y-117625D02*
Y-102034D01*
G01X230060Y-117626D02*
G03X232080I1010J239D01*
G01X226590Y-116472D02*
G03X225311Y-115210I-817J451D01*
G01X234673Y-114020D02*
G03X237849Y-118061I6190J1597D01*
G01X232081Y-102041D02*
Y-117625D01*
G01X219083Y-115753D02*
G03X225311Y-115211I2844J3371D01*
G01X219079Y-118060D02*
G03X226591Y-116473I2662J5972D01*
G01X227413Y-111835D02*
Y-112869D01*
G01X232080Y-102041D02*
G03X230060Y-102034I-1011J-236D01*
G01X225188Y-111399D02*
Y-111418D01*
G01X234675Y-114020D02*
Y-111835D01*
G01X246181D02*
G03X234675I-5753J223D01*
G01X252849Y-116771D02*
G03X254892Y-115895I-74J2994D01*
G01X236844Y-112869D02*
G03X237852Y-115752I4343J-99D01*
G01X237848Y-118060D02*
G03X245360Y-116473I2662J5972D01*
G01X245358Y-116472D02*
G03X244079Y-115210I-817J451D01*
G01X237852Y-115753D02*
G03X244080Y-115211I2844J3371D01*
G01X249566Y-115529D02*
G03X252307Y-116760I2985J2980D01*
G01Y-116761D02*
G03X252849Y-116772I366J4691D01*
G01X250282Y-118087D02*
G03X254318Y-118340I2605J9244D01*
G01X247897Y-116444D02*
G03X250283Y-118086I3752J2898D01*
G01X249568Y-115529D02*
G03X247898Y-116443I-748J-616D01*
G01X255608Y-108618D02*
G03X253612Y-107689I-3116J-4086D01*
G01X246181Y-111835D02*
Y-112869D01*
G01D02*
X236844D01*
G01X255002Y-114328D02*
G03X252723Y-112986I-3540J-3405D01*
G01X249955Y-112030D02*
G03X252723Y-112985I8208J19302D01*
G01X243957Y-111399D02*
Y-111418D01*
G01X243958Y-111399D02*
G03X236840I-3559J159D01*
G01X236841Y-111418D02*
Y-111399D01*
G01X243957Y-111418D02*
X236841D01*
G01X248537Y-109748D02*
G03X249956Y-112031I2652J66D01*
G01X248537Y-108250D02*
Y-109748D01*
G01X250179Y-106359D02*
G03X248537Y-108249I2747J-4045D01*
G01X256884Y-107368D02*
G03X250178Y-106359I-4153J-4811D01*
G01X253611Y-107689D02*
G03X251080Y-107949I-869J-3992D01*
G01X251081Y-107948D02*
G03X250837Y-110104I805J-1183D01*
G01Y-110106D02*
G03X254306Y-111513I5270J8013D01*
G01X260954Y-116041D02*
Y-107954D01*
G01X254892Y-115895D02*
G03X255001Y-114328I-764J840D01*
G01X269619Y-117484D02*
Y-106797D01*
G01X269620Y-117484D02*
G03X271926I1153J198D01*
G01X266864Y-117375D02*
G03X266002Y-116329I-764J249D01*
G01X262978Y-115462D02*
G03X266002Y-116329I2046J1428D01*
G01X260955Y-116043D02*
G03X264164Y-118351I2956J725D01*
G01X265463Y-118350D02*
X264165D01*
G01X265464Y-118352D02*
G03X266864Y-117374I-24J1525D01*
G01X256906Y-116470D02*
G03X257054Y-113728I-3143J1545D01*
G01X254317Y-118340D02*
G03X256906Y-116470I-1259J4470D01*
G01X262978Y-107954D02*
Y-115463D01*
G01X257054Y-113729D02*
G03X254307Y-111513I-3470J-1490D01*
G01X271969Y-102342D02*
G03I-1194J0D01*
G01X271926Y-106797D02*
G03X269620I-1153J-409D01*
G01X266003Y-107954D02*
X262978D01*
G01X266004Y-107955D02*
G03X266008Y-105932I-177J1012D01*
G01X262978D02*
X266008D01*
G01X262971Y-103419D02*
X262978Y-105932D01*
G01X262972Y-103418D02*
G03X260954Y-103491I-1005J-141D01*
G01Y-105932D02*
Y-103492D01*
G01X259930Y-105932D02*
X260954D01*
G01X259930D02*
G03X259981Y-107955I298J-1005D01*
G01X260954Y-107954D02*
X259982D01*
G01X255606Y-108620D02*
G03X256885Y-107367I599J667D01*
G01X290671Y-110842D02*
G03X290703Y-118351I860J-3751D01*
G01X276837Y-114305D02*
G03X278891Y-116297I4069J2141D01*
G01X274529Y-113568D02*
G03X275888Y-116443I5718J944D01*
G01X275887D02*
G03X279572Y-118352I4392J3967D01*
G01X281425Y-118350D02*
X279571D01*
G01X281425D02*
G03X284525Y-117161I0J4636D01*
G01X285201Y-116508D02*
X284524Y-117161D01*
G01X285201Y-116508D02*
G03X283966Y-115211I-695J574D01*
G01X281510Y-116675D02*
G03X283966Y-115212I-989J4453D01*
G01X278889Y-116297D02*
G03X281508Y-116677I1946J4197D01*
G01X271926Y-106797D02*
Y-117484D01*
G01X274529Y-113566D02*
Y-111839D01*
G01X276446Y-112943D02*
G03X276837Y-114305I4162J458D01*
G01X276445Y-112066D02*
Y-112943D01*
G01X283833Y-109274D02*
G03X285403Y-108106I585J852D01*
G01X285402D02*
G03X280919Y-105777I-4776J-3714D01*
G01X279541D02*
X280919D01*
G01X279540D02*
G03X274999Y-109274I1260J-6333D01*
G01X274998D02*
G03X274529Y-111839I9988J-3152D01*
G01X276849Y-109932D02*
G03X276446Y-112066I5467J-2137D01*
G01X280036Y-107542D02*
G03X276849Y-109933I664J-4205D01*
G01X282662Y-108199D02*
G03X280037Y-107539I-2313J-3650D01*
G01X283833Y-109275D02*
G03X282662Y-108202I-9277J-8949D01*
G01X294457Y-116619D02*
G03Y-112289I-51J2165D01*
G01X291853Y-116620D02*
X294456D01*
G01X291853Y-112289D02*
G03Y-116619I195J-2165D01*
G01X294165Y-118350D02*
X290701D01*
G01X294165D02*
G03X296471Y-117226I-1088J5161D01*
G01X296473Y-117625D02*
Y-117226D01*
G01X296474Y-117627D02*
G03X298494I1010J185D01*
G01X298495Y-109394D02*
Y-117625D01*
G01X301067Y-108534D02*
Y-106508D01*
G01X301615Y-108534D02*
X301067D01*
G01X301615Y-106508D02*
Y-108534D01*
G01X302461Y-106508D02*
X301615D01*
G01X302461Y-106001D02*
Y-106508D01*
G01X300223Y-106001D02*
X302461D01*
G01X300223Y-106508D02*
Y-106001D01*
G01X301067Y-106508D02*
X300223D01*
G01X305164Y-106001D02*
X304731D01*
G01X305713Y-108544D02*
X305164Y-106001D01*
G01X305171Y-108544D02*
X305713D01*
G01X304889Y-106871D02*
X305171Y-108544D01*
G01X304309D02*
X304889Y-106871D01*
G01X304086Y-108544D02*
X304309D01*
G01X303501Y-106887D02*
X304086Y-108544D01*
G01X303226D02*
X303501Y-106887D01*
G01X302698Y-108544D02*
X303226D01*
G01X303243Y-106001D02*
X302698Y-108544D01*
G01X303648Y-106001D02*
X303243D01*
G01X304192Y-107632D02*
X303648Y-106001D01*
G01X304731D02*
X304192Y-107632D01*
G01X294456Y-112288D02*
X291853D01*
G01X296473Y-110841D02*
Y-109686D01*
G01X296472Y-110841D02*
G03X292878Y-110536I-3256J-17043D01*
G01X292879Y-110535D02*
G03X290670Y-110842I280J-10112D01*
G01X298496Y-109394D02*
G03X295031Y-105933I-3962J-501D01*
G01X291563Y-105932D02*
X295031D01*
G01X291562D02*
G03X289112Y-107085I584J-4421D01*
G01Y-107086D02*
G03X289820Y-108520I585J-603D01*
G01X290987Y-107954D02*
G03X289821Y-108520I1446J-4464D01*
G01X294740Y-107954D02*
X290987D01*
G01X296473Y-109686D02*
G03X294742Y-107955I-1598J133D01*
G01X381000Y-125000D02*
Y-133000D01*
X385000D01*
G01X391000Y-125000D02*
X390200Y-125267D01*
X389600Y-125933D01*
X389200Y-126733D01*
X388900Y-127800D01*
X388800Y-129000D01*
X388900Y-130200D01*
X389200Y-131267D01*
X389600Y-132067D01*
X390200Y-132733D01*
X391000Y-133000D01*
X391800Y-132733D01*
X392400Y-132067D01*
X392800Y-131267D01*
X393100Y-130200D01*
X393200Y-129000D01*
X393100Y-127800D01*
X392800Y-126733D01*
X392400Y-125933D01*
X391800Y-125267D01*
X391000Y-125000D01*
G01X397300Y-132067D02*
X398000Y-132733D01*
X398800Y-133000D01*
X399600Y-132733D01*
X400300Y-131934D01*
X400800Y-130733D01*
X401000Y-129533D01*
Y-128067D01*
X400800Y-126867D01*
X400300Y-125800D01*
X399700Y-125267D01*
X399000Y-125000D01*
X398200Y-125267D01*
X397600Y-125800D01*
X397200Y-126600D01*
X397000Y-127667D01*
X397200Y-128600D01*
X397700Y-129533D01*
X398300Y-130067D01*
X399000Y-130200D01*
X399800Y-129934D01*
X400400Y-129267D01*
X401000Y-128067D01*
G01X404000Y-135667D02*
X410000D01*
G01X415600Y-129000D02*
X417600D01*
Y-131400D01*
X417000Y-132200D01*
X416300Y-132733D01*
X415300Y-133000D01*
X414300Y-132733D01*
X413600Y-132200D01*
X413000Y-131400D01*
X412600Y-130467D01*
X412400Y-129400D01*
Y-128467D01*
X412600Y-127667D01*
X413000Y-126733D01*
X413600Y-125933D01*
X414200Y-125400D01*
X415000Y-125000D01*
X415700D01*
X416500Y-125267D01*
X417100Y-125800D01*
G01X420700Y-133000D02*
Y-125000D01*
X425300Y-133000D01*
Y-125000D01*
G01X428800Y-133000D02*
Y-125000D01*
X430800D01*
X431600Y-125400D01*
X432200Y-125933D01*
X432700Y-126733D01*
X433100Y-127667D01*
X433200Y-129000D01*
X433100Y-130333D01*
X432700Y-131267D01*
X432200Y-132067D01*
X431600Y-132600D01*
X430800Y-133000D01*
X428800D01*
G01X440200D02*
Y-125000D01*
X436500Y-130733D01*
X441500D01*
G54D16*
X17500Y91000D03*
X17000Y204500D03*
X19900Y283000D03*
X16000Y302500D03*
Y307500D03*
X45500Y126000D03*
Y161000D03*
X42000Y236800D03*
X51772Y73600D03*
X47600Y68900D03*
X47000Y100000D03*
X61400Y104900D03*
X51772Y130500D03*
X53900Y157000D03*
X60600Y161200D03*
X51772Y187987D03*
X57500Y218500D03*
X51772Y245074D03*
X48500Y271500D03*
X57500Y289000D03*
X61489Y332329D03*
X63500Y359600D03*
X67700Y65000D03*
X66400Y77400D03*
X66000Y91100D03*
X69500Y100000D03*
X74593Y202207D03*
X71400Y221700D03*
X67500Y222900D03*
X71500Y247800D03*
X80148Y253648D03*
X72000Y335000D03*
X66000Y419000D03*
X88900Y67000D03*
X83300Y87100D03*
X94500Y105000D03*
X86600Y141300D03*
X85750Y202750D03*
X93032Y246477D03*
X87200Y258300D03*
X98700Y268300D03*
X95593Y333347D03*
X94000Y420000D03*
X83000Y417000D03*
X103800Y76240D03*
X98800Y272400D03*
X104500Y305500D03*
X99000Y350000D03*
X103000Y364000D03*
X106500D03*
X110000D03*
X115500Y389000D03*
X102500Y420000D03*
X119500Y57694D03*
X127500Y290500D03*
X125095Y306095D03*
X123500Y347500D03*
X120000Y364500D03*
X129000Y365000D03*
Y370500D03*
X120000Y368000D03*
Y371500D03*
X132000Y379000D03*
X118500D03*
X132000Y375500D03*
X127000Y397061D03*
X117000Y397000D03*
X121169Y396892D03*
X150860Y67400D03*
X145000Y296500D03*
X141000Y298500D03*
X142130Y325630D03*
X140900Y355400D03*
X142000Y350000D03*
X148000Y370000D03*
X140123Y391604D03*
X135500Y383000D03*
Y390500D03*
X140100Y395600D03*
X135500Y396000D03*
X165000Y294000D03*
X166150Y304050D03*
X166700Y338800D03*
X151000Y324200D03*
X159100Y350400D03*
X151500Y370000D03*
X168500Y294000D03*
X169850Y298950D03*
X178600Y378600D03*
Y374600D03*
X175100Y382600D03*
Y387100D03*
X174600Y401600D03*
Y406100D03*
Y410600D03*
X176000Y416000D03*
X192160Y77840D03*
X190000Y301500D03*
Y305500D03*
X189500Y319000D03*
X189000Y326000D03*
X191500Y413000D03*
X215000Y69000D03*
X220000D03*
X218000Y381100D03*
X217600Y415100D03*
X228500Y382500D03*
X221500Y378500D03*
X226000D03*
X221500Y415000D03*
X225600Y415100D03*
X229500Y415000D03*
X254000Y213500D03*
X241441Y215000D03*
X241900Y238800D03*
X272330Y54871D03*
X259500Y70100D03*
X271000Y184500D03*
X269000Y215000D03*
X259000Y223000D03*
X282200Y179121D03*
X275260Y223000D03*
X280500Y224300D03*
X288000Y293000D03*
X288500Y317000D03*
X303500Y69400D03*
X298500Y184500D03*
X292000Y294720D03*
X299500Y295500D03*
X301000Y312000D03*
X311000Y193500D03*
X312000Y217000D03*
X308967Y204000D03*
X312000Y234400D03*
X311600Y252400D03*
X314500Y276500D03*
X312000Y295500D03*
X321899Y343000D03*
X321300Y423600D03*
X324800Y415200D03*
X321300Y416700D03*
X324800Y410700D03*
X341500Y233500D03*
X340953Y237000D03*
X328500Y258900D03*
X330500Y291500D03*
X338000Y315000D03*
X326000Y374000D03*
X325300Y387200D03*
X331500Y376000D03*
X338500D03*
X342000D03*
X325300Y396200D03*
Y391700D03*
X354000Y128000D03*
X351000Y130500D03*
X353500D03*
X356000D03*
X350100Y169400D03*
X352600D03*
X357600D03*
X355100D03*
X347300Y179000D03*
X351200Y196600D03*
X350500Y229500D03*
X355000Y242500D03*
X354975Y247900D03*
X343500Y258900D03*
X349000Y303000D03*
X355500Y306500D03*
X360000Y402400D03*
X376838Y100230D03*
X367000Y126000D03*
X374300Y129000D03*
X371800D03*
X374300Y132000D03*
X371800D03*
X363600Y176600D03*
X367600Y169300D03*
X364700Y169400D03*
X369560Y213000D03*
X372060D03*
X367000D03*
X364500D03*
X367000Y232000D03*
X372500D03*
X360500Y243000D03*
X367000Y241243D03*
X369500Y267500D03*
X362300Y286100D03*
X365800D03*
X374800Y291100D03*
X370300D03*
X361500Y296100D03*
X365800Y291100D03*
X362100Y291000D03*
X363100Y418300D03*
X360311Y409880D03*
X363100Y422800D03*
X384000Y102980D03*
Y109500D03*
X379800Y177100D03*
X380000Y204500D03*
X378000Y273500D03*
X388650Y292650D03*
X378000Y293200D03*
X383000D03*
X393300Y312500D03*
X383000Y341500D03*
X384300Y368700D03*
X383900Y372600D03*
X407000Y120000D03*
X399500D03*
X399000Y221407D03*
Y225000D03*
X397800Y259300D03*
X403700D03*
X399800Y278400D03*
X409100Y281300D03*
X409300Y286300D03*
X409200Y291700D03*
X397500Y312900D03*
X407500Y305000D03*
X397300Y320700D03*
X398000Y352000D03*
X410000Y358543D03*
X409650Y403950D03*
X412350Y401250D03*
Y397150D03*
X409650Y394450D03*
X422000Y77500D03*
X413500Y88500D03*
X423000Y100500D03*
X427800Y100300D03*
X429400Y107500D03*
X417500Y352000D03*
X419150Y394450D03*
X416450Y401250D03*
Y397150D03*
X419150Y403950D03*
X434500Y77000D03*
X441400Y78100D03*
X433500Y100500D03*
X444200D03*
X431000Y116500D03*
X444000Y226000D03*
Y250000D03*
X439500Y266500D03*
X444000Y263000D03*
X447200Y347500D03*
X446000Y374500D03*
X431000Y416000D03*
X448430Y89540D03*
X463500Y86500D03*
X450000Y108200D03*
X454600Y108500D03*
X462000Y224500D03*
Y250000D03*
X460000Y284500D03*
Y289500D03*
X459500Y322000D03*
X459000Y326000D03*
X454000Y393500D03*
Y397000D03*
X450000Y407000D03*
X481000Y70700D03*
X479867Y138867D03*
X481500Y182016D03*
X478000Y198000D03*
X471000Y259200D03*
X477500Y259000D03*
X471000Y347000D03*
X471400Y363300D03*
X489400Y126300D03*
X493300Y121500D03*
X496000Y167500D03*
Y179258D03*
X496500Y192500D03*
X496000Y205500D03*
X492500Y272200D03*
X491800Y277700D03*
X503950Y143000D03*
X512100Y249500D03*
X507100Y240700D03*
X512100D03*
Y244700D03*
Y262500D03*
X512300Y254400D03*
X512200Y258700D03*
X512650Y268150D03*
X511900Y276200D03*
X508950Y273250D03*
X506100Y280600D03*
X505000Y379500D03*
X504500Y376000D03*
X533000Y87000D03*
X533500Y124500D03*
X534000Y160500D03*
X517000Y212500D03*
X533200Y220000D03*
X529800Y223000D03*
X530350Y257480D03*
X532500Y272500D03*
X532900Y318900D03*
X527600D03*
X532400Y340600D03*
Y345600D03*
X527100Y340600D03*
Y345600D03*
X532200Y377700D03*
X523700Y384100D03*
X528200Y377700D03*
X523700D03*
X525176Y411925D03*
X543957Y60543D03*
X537000Y69000D03*
X534500Y130000D03*
Y136500D03*
X534600Y148300D03*
Y152000D03*
X544000Y159000D03*
X542500Y189500D03*
X538500D03*
X540900Y201500D03*
X543500Y205000D03*
X536900Y201500D03*
X549000Y267500D03*
X551700Y256300D03*
X541346Y303507D03*
X538600Y318900D03*
X538100Y340600D03*
Y345600D03*
X548557Y387700D03*
X538500Y407875D03*
X543000Y396700D03*
X562500Y74600D03*
X560650Y70450D03*
X559941Y62120D03*
X563341Y62102D03*
X564350Y65350D03*
X559000Y85000D03*
X560200Y81500D03*
X559000Y88800D03*
X568700Y204300D03*
X564700Y204400D03*
X553800Y240200D03*
X563700Y352400D03*
X564500Y379000D03*
X560200Y386500D03*
X580500Y65800D03*
X580643Y60900D03*
X585900Y79600D03*
X576459Y161971D03*
X575072Y165500D03*
X580500Y194500D03*
X583000Y192000D03*
X573200Y204300D03*
X586500Y230000D03*
X581500Y267000D03*
X581400Y292250D03*
X580300Y356700D03*
X576300Y371200D03*
X580200Y361700D03*
X580100Y366700D03*
X580300Y380700D03*
Y375700D03*
Y385700D03*
X599000Y92500D03*
X592000Y136000D03*
X597703Y187000D03*
X616500Y194874D03*
X614100Y224100D03*
X610500Y227000D03*
X622000Y136000D03*
X633500Y196874D03*
X636000Y216142D03*
X626989Y237989D03*
X633500Y301500D03*
X647000Y113500D03*
M02*
